FILE_TYPE = MACRO_DRAWING;
SET COLOR_WIRE YELLOW;
SET COLOR_PROP ORANGE;
SET COLOR_DOT WHITE;
SET COLOR_ARC YELLOW;
SET COLOR_BODY GREEN;
SET COLOR_NOTE PURPLE;
SET PROP_DISPLAY VALUE;
SET PAGE_NUMBER P24;
FORCEADD GENOA_SP5..15
(-4925 5000);
FORCEPROP 1 LAST LOCATION U25
J 0
(-6020 6256);
DISPLAY 0.489362 (-6020 6256);
PAINT SKYBLUE (-6020 6256);
FORCEPROP 0 LAST $SEC 15
J 0
(-6000 6300);
DISPLAY 0.680851 (-6000 6300);
PAINT MONO (-6000 6300);
DISPLAY INVISIBLE (-6000 6300);
FORCEPROP 0 LAST CDS_SEC 15
J 0
(-6025 6225);
DISPLAY 1.021277 (-6025 6225);
DISPLAY INVISIBLE (-6025 6225);
FORCEPROP 0 LASTPIN (-6175 5750) $PN BW53
J 2
(-6185 5760);
DISPLAY 0.489362 (-6185 5760);
PAINT MONO (-6185 5760);
FORCEPROP 0 LASTPIN (-6175 5650) $PN CA53
J 2
(-6185 5660);
DISPLAY 0.489362 (-6185 5660);
PAINT MONO (-6185 5660);
FORCEPROP 0 LASTPIN (-6175 5550) $PN BU53
J 2
(-6185 5560);
DISPLAY 0.489362 (-6185 5560);
PAINT MONO (-6185 5560);
FORCEPROP 0 LASTPIN (-6175 5450) $PN BW50
J 2
(-6185 5460);
DISPLAY 0.489362 (-6185 5460);
PAINT MONO (-6185 5460);
FORCEPROP 0 LASTPIN (-6175 5350) $PN CA50
J 2
(-6185 5360);
DISPLAY 0.489362 (-6185 5360);
PAINT MONO (-6185 5360);
FORCEPROP 0 LASTPIN (-6175 5250) $PN BU50
J 2
(-6185 5260);
DISPLAY 0.489362 (-6185 5260);
PAINT MONO (-6185 5260);
FORCEPROP 0 LASTPIN (-6175 5150) $PN BW47
J 2
(-6185 5160);
DISPLAY 0.489362 (-6185 5160);
PAINT MONO (-6185 5160);
FORCEPROP 0 LASTPIN (-6175 5050) $PN CA47
J 2
(-6185 5060);
DISPLAY 0.489362 (-6185 5060);
PAINT MONO (-6185 5060);
FORCEPROP 0 LASTPIN (-6175 4950) $PN BU47
J 2
(-6185 4960);
DISPLAY 0.489362 (-6185 4960);
PAINT MONO (-6185 4960);
FORCEPROP 0 LASTPIN (-6175 4850) $PN BW44
J 2
(-6185 4860);
DISPLAY 0.489362 (-6185 4860);
PAINT MONO (-6185 4860);
FORCEPROP 0 LASTPIN (-6175 4750) $PN CA44
J 2
(-6185 4760);
DISPLAY 0.489362 (-6185 4760);
PAINT MONO (-6185 4760);
FORCEPROP 0 LASTPIN (-6175 4650) $PN BU44
J 2
(-6185 4660);
DISPLAY 0.489362 (-6185 4660);
PAINT MONO (-6185 4660);
FORCEPROP 0 LASTPIN (-6175 4550) $PN BY41
J 2
(-6185 4560);
DISPLAY 0.489362 (-6185 4560);
PAINT MONO (-6185 4560);
FORCEPROP 0 LASTPIN (-6175 4450) $PN CB41
J 2
(-6185 4460);
DISPLAY 0.489362 (-6185 4460);
PAINT MONO (-6185 4460);
FORCEPROP 0 LASTPIN (-6175 4350) $PN BV41
J 2
(-6185 4360);
DISPLAY 0.489362 (-6185 4360);
PAINT MONO (-6185 4360);
FORCEPROP 0 LASTPIN (-6175 4250) $PN BT41
J 2
(-6185 4260);
DISPLAY 0.489362 (-6185 4260);
PAINT MONO (-6185 4260);
FORCEPROP 0 LASTPIN (-6175 5800) $PN BW52
J 2
(-6185 5810);
DISPLAY 0.489362 (-6185 5810);
PAINT MONO (-6185 5810);
FORCEPROP 0 LASTPIN (-6175 5700) $PN CA52
J 2
(-6185 5710);
DISPLAY 0.489362 (-6185 5710);
PAINT MONO (-6185 5710);
FORCEPROP 0 LASTPIN (-6175 5600) $PN BU52
J 2
(-6185 5610);
DISPLAY 0.489362 (-6185 5610);
PAINT MONO (-6185 5610);
FORCEPROP 0 LASTPIN (-6175 5500) $PN BW49
J 2
(-6185 5510);
DISPLAY 0.489362 (-6185 5510);
PAINT MONO (-6185 5510);
FORCEPROP 0 LASTPIN (-6175 5400) $PN CA49
J 2
(-6185 5410);
DISPLAY 0.489362 (-6185 5410);
PAINT MONO (-6185 5410);
FORCEPROP 0 LASTPIN (-6175 5300) $PN BU49
J 2
(-6185 5310);
DISPLAY 0.489362 (-6185 5310);
PAINT MONO (-6185 5310);
FORCEPROP 0 LASTPIN (-6175 5200) $PN BW46
J 2
(-6185 5210);
DISPLAY 0.489362 (-6185 5210);
PAINT MONO (-6185 5210);
FORCEPROP 0 LASTPIN (-6175 5100) $PN CA46
J 2
(-6185 5110);
DISPLAY 0.489362 (-6185 5110);
PAINT MONO (-6185 5110);
FORCEPROP 0 LASTPIN (-6175 5000) $PN BU46
J 2
(-6185 5010);
DISPLAY 0.489362 (-6185 5010);
PAINT MONO (-6185 5010);
FORCEPROP 0 LASTPIN (-6175 4900) $PN BW43
J 2
(-6185 4910);
DISPLAY 0.489362 (-6185 4910);
PAINT MONO (-6185 4910);
FORCEPROP 0 LASTPIN (-6175 4800) $PN CA43
J 2
(-6185 4810);
DISPLAY 0.489362 (-6185 4810);
PAINT MONO (-6185 4810);
FORCEPROP 0 LASTPIN (-6175 4700) $PN BU43
J 2
(-6185 4710);
DISPLAY 0.489362 (-6185 4710);
PAINT MONO (-6185 4710);
FORCEPROP 0 LASTPIN (-6175 4600) $PN BY40
J 2
(-6185 4610);
DISPLAY 0.489362 (-6185 4610);
PAINT MONO (-6185 4610);
FORCEPROP 0 LASTPIN (-6175 4500) $PN CB40
J 2
(-6185 4510);
DISPLAY 0.489362 (-6185 4510);
PAINT MONO (-6185 4510);
FORCEPROP 0 LASTPIN (-6175 4400) $PN BV40
J 2
(-6185 4410);
DISPLAY 0.489362 (-6185 4410);
PAINT MONO (-6185 4410);
FORCEPROP 0 LASTPIN (-6175 4300) $PN BT40
J 2
(-6185 4310);
DISPLAY 0.489362 (-6185 4310);
PAINT MONO (-6185 4310);
FORCEPROP 0 LASTPIN (-3675 5750) $PN CN52
J 0
(-3665 5760);
DISPLAY 0.489362 (-3665 5760);
PAINT MONO (-3665 5760);
FORCEPROP 0 LASTPIN (-3675 5650) $PN CR52
J 0
(-3665 5660);
DISPLAY 0.489362 (-3665 5660);
PAINT MONO (-3665 5660);
FORCEPROP 0 LASTPIN (-3675 5550) $PN CL52
J 0
(-3665 5560);
DISPLAY 0.489362 (-3665 5560);
PAINT MONO (-3665 5560);
FORCEPROP 0 LASTPIN (-3675 5450) $PN CN49
J 0
(-3665 5460);
DISPLAY 0.489362 (-3665 5460);
PAINT MONO (-3665 5460);
FORCEPROP 0 LASTPIN (-3675 5350) $PN CR49
J 0
(-3665 5360);
DISPLAY 0.489362 (-3665 5360);
PAINT MONO (-3665 5360);
FORCEPROP 0 LASTPIN (-3675 5250) $PN CU49
J 0
(-3665 5260);
DISPLAY 0.489362 (-3665 5260);
PAINT MONO (-3665 5260);
FORCEPROP 0 LASTPIN (-3675 5150) $PN CL49
J 0
(-3665 5160);
DISPLAY 0.489362 (-3665 5160);
PAINT MONO (-3665 5160);
FORCEPROP 0 LASTPIN (-3675 5050) $PN CR46
J 0
(-3665 5060);
DISPLAY 0.489362 (-3665 5060);
PAINT MONO (-3665 5060);
FORCEPROP 0 LASTPIN (-3675 4950) $PN CU46
J 0
(-3665 4960);
DISPLAY 0.489362 (-3665 4960);
PAINT MONO (-3665 4960);
FORCEPROP 0 LASTPIN (-3675 4850) $PN CN46
J 0
(-3665 4860);
DISPLAY 0.489362 (-3665 4860);
PAINT MONO (-3665 4860);
FORCEPROP 0 LASTPIN (-3675 4750) $PN CR43
J 0
(-3665 4760);
DISPLAY 0.489362 (-3665 4760);
PAINT MONO (-3665 4760);
FORCEPROP 0 LASTPIN (-3675 4650) $PN CU43
J 0
(-3665 4660);
DISPLAY 0.489362 (-3665 4660);
PAINT MONO (-3665 4660);
FORCEPROP 0 LASTPIN (-3675 4550) $PN CN43
J 0
(-3665 4560);
DISPLAY 0.489362 (-3665 4560);
PAINT MONO (-3665 4560);
FORCEPROP 0 LASTPIN (-3675 4450) $PN CT40
J 0
(-3665 4460);
DISPLAY 0.489362 (-3665 4460);
PAINT MONO (-3665 4460);
FORCEPROP 0 LASTPIN (-3675 4350) $PN CP40
J 0
(-3665 4360);
DISPLAY 0.489362 (-3665 4360);
PAINT MONO (-3665 4360);
FORCEPROP 0 LASTPIN (-3675 4250) $PN CM40
J 0
(-3665 4260);
DISPLAY 0.489362 (-3665 4260);
PAINT MONO (-3665 4260);
FORCEPROP 0 LASTPIN (-3675 5800) $PN CN53
J 0
(-3665 5810);
DISPLAY 0.489362 (-3665 5810);
PAINT MONO (-3665 5810);
FORCEPROP 0 LASTPIN (-3675 5700) $PN CR53
J 0
(-3665 5710);
DISPLAY 0.489362 (-3665 5710);
PAINT MONO (-3665 5710);
FORCEPROP 0 LASTPIN (-3675 5600) $PN CL53
J 0
(-3665 5610);
DISPLAY 0.489362 (-3665 5610);
PAINT MONO (-3665 5610);
FORCEPROP 0 LASTPIN (-3675 5500) $PN CN50
J 0
(-3665 5510);
DISPLAY 0.489362 (-3665 5510);
PAINT MONO (-3665 5510);
FORCEPROP 0 LASTPIN (-3675 5400) $PN CR50
J 0
(-3665 5410);
DISPLAY 0.489362 (-3665 5410);
PAINT MONO (-3665 5410);
FORCEPROP 0 LASTPIN (-3675 5300) $PN CU50
J 0
(-3665 5310);
DISPLAY 0.489362 (-3665 5310);
PAINT MONO (-3665 5310);
FORCEPROP 0 LASTPIN (-3675 5200) $PN CL50
J 0
(-3665 5210);
DISPLAY 0.489362 (-3665 5210);
PAINT MONO (-3665 5210);
FORCEPROP 0 LASTPIN (-3675 5100) $PN CR47
J 0
(-3665 5110);
DISPLAY 0.489362 (-3665 5110);
PAINT MONO (-3665 5110);
FORCEPROP 0 LASTPIN (-3675 5000) $PN CU47
J 0
(-3665 5010);
DISPLAY 0.489362 (-3665 5010);
PAINT MONO (-3665 5010);
FORCEPROP 0 LASTPIN (-3675 4900) $PN CN47
J 0
(-3665 4910);
DISPLAY 0.489362 (-3665 4910);
PAINT MONO (-3665 4910);
FORCEPROP 0 LASTPIN (-3675 4800) $PN CR44
J 0
(-3665 4810);
DISPLAY 0.489362 (-3665 4810);
PAINT MONO (-3665 4810);
FORCEPROP 0 LASTPIN (-3675 4700) $PN CU44
J 0
(-3665 4710);
DISPLAY 0.489362 (-3665 4710);
PAINT MONO (-3665 4710);
FORCEPROP 0 LASTPIN (-3675 4600) $PN CN44
J 0
(-3665 4610);
DISPLAY 0.489362 (-3665 4610);
PAINT MONO (-3665 4610);
FORCEPROP 0 LASTPIN (-3675 4500) $PN CT41
J 0
(-3665 4510);
DISPLAY 0.489362 (-3665 4510);
PAINT MONO (-3665 4510);
FORCEPROP 0 LASTPIN (-3675 4400) $PN CP41
J 0
(-3665 4410);
DISPLAY 0.489362 (-3665 4410);
PAINT MONO (-3665 4410);
FORCEPROP 0 LASTPIN (-3675 4300) $PN CM41
J 0
(-3665 4310);
DISPLAY 0.489362 (-3665 4310);
PAINT MONO (-3665 4310);
FORCEPROP 2 LAST VALUE SOCKET6096_13568-001
J 0
(-6025 6053);
DISPLAY 0.489362 (-6025 6053);
PAINT SKYBLUE (-6025 6053);
FORCEPROP 1 LAST MATERIAL IO
J 0
(-6020 5982);
DISPLAY 0.489362 (-6020 5982);
PAINT SKYBLUE (-6020 5982);
FORCEPROP 2 LAST PART_TYPE SMLF
J 0
(-6025 6153);
DISPLAY 1.021277 (-6025 6153);
FORCEPROP 1 LAST PART_NUMBER DGA^6000030
J 0
(-6020 6109);
DISPLAY 0.489362 (-6020 6109);
PAINT SKYBLUE (-6020 6109);
FORCEPROP 2 LAST CDS_LIB pure_quanta
J 0
(-4925 5000);
DISPLAY INVISIBLE (-4925 5000);
FORCEPROP 1 LAST NEEDS_NO_SIZE TRUE
J 0
(-4925 5000);
DISPLAY 0.723404 (-4925 5000);
PAINT GREEN (-4925 5000);
DISPLAY INVISIBLE (-4925 5000);
FORCEPROP 1 LAST CDS_LMAN_SYM_OUTLINE -1100,950,1100,-950
J 0
(-4925 5000);
DISPLAY 0.468085 (-4925 5000);
PAINT GREEN (-4925 5000);
DISPLAY INVISIBLE (-4925 5000);
FORCEPROP 1 LAST PATH I148
J 0
(-4925 5000);
DISPLAY 0.723404 (-4925 5000);
PAINT GREEN (-4925 5000);
DISPLAY INVISIBLE (-4925 5000);
FORCEADD GENOA_SP5..16
(-5000 1525);
FORCEPROP 1 LAST LOCATION U25
J 0
(-6100 2781);
DISPLAY 0.489362 (-6100 2781);
PAINT SKYBLUE (-6100 2781);
FORCEPROP 0 LAST $SEC 16
J 0
(-6075 2825);
DISPLAY 0.680851 (-6075 2825);
PAINT MONO (-6075 2825);
DISPLAY INVISIBLE (-6075 2825);
FORCEPROP 0 LAST CDS_SEC 16
J 0
(-6100 2675);
DISPLAY 1.021277 (-6100 2675);
DISPLAY INVISIBLE (-6100 2675);
FORCEPROP 0 LASTPIN (-6250 2275) $PN CE53
J 2
(-6260 2285);
DISPLAY 0.489362 (-6260 2285);
PAINT MONO (-6260 2285);
FORCEPROP 0 LASTPIN (-6250 2175) $PN CG53
J 2
(-6260 2185);
DISPLAY 0.489362 (-6260 2185);
PAINT MONO (-6260 2185);
FORCEPROP 0 LASTPIN (-6250 2075) $PN CC53
J 2
(-6260 2085);
DISPLAY 0.489362 (-6260 2085);
PAINT MONO (-6260 2085);
FORCEPROP 0 LASTPIN (-6250 1975) $PN CE50
J 2
(-6260 1985);
DISPLAY 0.489362 (-6260 1985);
PAINT MONO (-6260 1985);
FORCEPROP 0 LASTPIN (-6250 1875) $PN CG50
J 2
(-6260 1885);
DISPLAY 0.489362 (-6260 1885);
PAINT MONO (-6260 1885);
FORCEPROP 0 LASTPIN (-6250 1775) $PN CC50
J 2
(-6260 1785);
DISPLAY 0.489362 (-6260 1785);
PAINT MONO (-6260 1785);
FORCEPROP 0 LASTPIN (-6250 1675) $PN CE47
J 2
(-6260 1685);
DISPLAY 0.489362 (-6260 1685);
PAINT MONO (-6260 1685);
FORCEPROP 0 LASTPIN (-6250 1575) $PN CG47
J 2
(-6260 1585);
DISPLAY 0.489362 (-6260 1585);
PAINT MONO (-6260 1585);
FORCEPROP 0 LASTPIN (-6250 1475) $PN CC47
J 2
(-6260 1485);
DISPLAY 0.489362 (-6260 1485);
PAINT MONO (-6260 1485);
FORCEPROP 0 LASTPIN (-6250 1375) $PN CE44
J 2
(-6260 1385);
DISPLAY 0.489362 (-6260 1385);
PAINT MONO (-6260 1385);
FORCEPROP 0 LASTPIN (-6250 1275) $PN CG44
J 2
(-6260 1285);
DISPLAY 0.489362 (-6260 1285);
PAINT MONO (-6260 1285);
FORCEPROP 0 LASTPIN (-6250 1175) $PN CJ44
J 2
(-6260 1185);
DISPLAY 0.489362 (-6260 1185);
PAINT MONO (-6260 1185);
FORCEPROP 0 LASTPIN (-6250 1075) $PN CC44
J 2
(-6260 1085);
DISPLAY 0.489362 (-6260 1085);
PAINT MONO (-6260 1085);
FORCEPROP 0 LASTPIN (-6250 975) $PN CH41
J 2
(-6260 985);
DISPLAY 0.489362 (-6260 985);
PAINT MONO (-6260 985);
FORCEPROP 0 LASTPIN (-6250 875) $PN CF41
J 2
(-6260 885);
DISPLAY 0.489362 (-6260 885);
PAINT MONO (-6260 885);
FORCEPROP 0 LASTPIN (-6250 775) $PN CD41
J 2
(-6260 785);
DISPLAY 0.489362 (-6260 785);
PAINT MONO (-6260 785);
FORCEPROP 0 LASTPIN (-6250 2325) $PN CE52
J 2
(-6260 2335);
DISPLAY 0.489362 (-6260 2335);
PAINT MONO (-6260 2335);
FORCEPROP 0 LASTPIN (-6250 2225) $PN CG52
J 2
(-6260 2235);
DISPLAY 0.489362 (-6260 2235);
PAINT MONO (-6260 2235);
FORCEPROP 0 LASTPIN (-6250 2125) $PN CC52
J 2
(-6260 2135);
DISPLAY 0.489362 (-6260 2135);
PAINT MONO (-6260 2135);
FORCEPROP 0 LASTPIN (-6250 2025) $PN CE49
J 2
(-6260 2035);
DISPLAY 0.489362 (-6260 2035);
PAINT MONO (-6260 2035);
FORCEPROP 0 LASTPIN (-6250 1925) $PN CG49
J 2
(-6260 1935);
DISPLAY 0.489362 (-6260 1935);
PAINT MONO (-6260 1935);
FORCEPROP 0 LASTPIN (-6250 1825) $PN CC49
J 2
(-6260 1835);
DISPLAY 0.489362 (-6260 1835);
PAINT MONO (-6260 1835);
FORCEPROP 0 LASTPIN (-6250 1725) $PN CE46
J 2
(-6260 1735);
DISPLAY 0.489362 (-6260 1735);
PAINT MONO (-6260 1735);
FORCEPROP 0 LASTPIN (-6250 1625) $PN CG46
J 2
(-6260 1635);
DISPLAY 0.489362 (-6260 1635);
PAINT MONO (-6260 1635);
FORCEPROP 0 LASTPIN (-6250 1525) $PN CC46
J 2
(-6260 1535);
DISPLAY 0.489362 (-6260 1535);
PAINT MONO (-6260 1535);
FORCEPROP 0 LASTPIN (-6250 1425) $PN CE43
J 2
(-6260 1435);
DISPLAY 0.489362 (-6260 1435);
PAINT MONO (-6260 1435);
FORCEPROP 0 LASTPIN (-6250 1325) $PN CG43
J 2
(-6260 1335);
DISPLAY 0.489362 (-6260 1335);
PAINT MONO (-6260 1335);
FORCEPROP 0 LASTPIN (-6250 1225) $PN CJ43
J 2
(-6260 1235);
DISPLAY 0.489362 (-6260 1235);
PAINT MONO (-6260 1235);
FORCEPROP 0 LASTPIN (-6250 1125) $PN CC43
J 2
(-6260 1135);
DISPLAY 0.489362 (-6260 1135);
PAINT MONO (-6260 1135);
FORCEPROP 0 LASTPIN (-6250 1025) $PN CH40
J 2
(-6260 1035);
DISPLAY 0.489362 (-6260 1035);
PAINT MONO (-6260 1035);
FORCEPROP 0 LASTPIN (-6250 925) $PN CF40
J 2
(-6260 935);
DISPLAY 0.489362 (-6260 935);
PAINT MONO (-6260 935);
FORCEPROP 0 LASTPIN (-6250 825) $PN CD40
J 2
(-6260 835);
DISPLAY 0.489362 (-6260 835);
PAINT MONO (-6260 835);
FORCEPROP 0 LASTPIN (-3750 2275) $PN CU52
J 0
(-3740 2285);
DISPLAY 0.489362 (-3740 2285);
PAINT MONO (-3740 2285);
FORCEPROP 0 LASTPIN (-3750 2175) $PN DA52
J 0
(-3740 2185);
DISPLAY 0.489362 (-3740 2185);
PAINT MONO (-3740 2185);
FORCEPROP 0 LASTPIN (-3750 2075) $PN DC52
J 0
(-3740 2085);
DISPLAY 0.489362 (-3740 2085);
PAINT MONO (-3740 2085);
FORCEPROP 0 LASTPIN (-3750 1975) $PN CW52
J 0
(-3740 1985);
DISPLAY 0.489362 (-3740 1985);
PAINT MONO (-3740 1985);
FORCEPROP 0 LASTPIN (-3750 1875) $PN DA49
J 0
(-3740 1885);
DISPLAY 0.489362 (-3740 1885);
PAINT MONO (-3740 1885);
FORCEPROP 0 LASTPIN (-3750 1775) $PN DC49
J 0
(-3740 1785);
DISPLAY 0.489362 (-3740 1785);
PAINT MONO (-3740 1785);
FORCEPROP 0 LASTPIN (-3750 1675) $PN CW49
J 0
(-3740 1685);
DISPLAY 0.489362 (-3740 1685);
PAINT MONO (-3740 1685);
FORCEPROP 0 LASTPIN (-3750 1575) $PN DA46
J 0
(-3740 1585);
DISPLAY 0.489362 (-3740 1585);
PAINT MONO (-3740 1585);
FORCEPROP 0 LASTPIN (-3750 1475) $PN DC46
J 0
(-3740 1485);
DISPLAY 0.489362 (-3740 1485);
PAINT MONO (-3740 1485);
FORCEPROP 0 LASTPIN (-3750 1375) $PN CW46
J 0
(-3740 1385);
DISPLAY 0.489362 (-3740 1385);
PAINT MONO (-3740 1385);
FORCEPROP 0 LASTPIN (-3750 1275) $PN DA43
J 0
(-3740 1285);
DISPLAY 0.489362 (-3740 1285);
PAINT MONO (-3740 1285);
FORCEPROP 0 LASTPIN (-3750 1175) $PN DC43
J 0
(-3740 1185);
DISPLAY 0.489362 (-3740 1185);
PAINT MONO (-3740 1185);
FORCEPROP 0 LASTPIN (-3750 1075) $PN CW43
J 0
(-3740 1085);
DISPLAY 0.489362 (-3740 1085);
PAINT MONO (-3740 1085);
FORCEPROP 0 LASTPIN (-3750 975) $PN DB40
J 0
(-3740 985);
DISPLAY 0.489362 (-3740 985);
PAINT MONO (-3740 985);
FORCEPROP 0 LASTPIN (-3750 875) $PN CY40
J 0
(-3740 885);
DISPLAY 0.489362 (-3740 885);
PAINT MONO (-3740 885);
FORCEPROP 0 LASTPIN (-3750 775) $PN CV40
J 0
(-3740 785);
DISPLAY 0.489362 (-3740 785);
PAINT MONO (-3740 785);
FORCEPROP 0 LASTPIN (-3750 2325) $PN CU53
J 0
(-3740 2335);
DISPLAY 0.489362 (-3740 2335);
PAINT MONO (-3740 2335);
FORCEPROP 0 LASTPIN (-3750 2225) $PN DA53
J 0
(-3740 2235);
DISPLAY 0.489362 (-3740 2235);
PAINT MONO (-3740 2235);
FORCEPROP 0 LASTPIN (-3750 2125) $PN DC53
J 0
(-3740 2135);
DISPLAY 0.489362 (-3740 2135);
PAINT MONO (-3740 2135);
FORCEPROP 0 LASTPIN (-3750 2025) $PN CW53
J 0
(-3740 2035);
DISPLAY 0.489362 (-3740 2035);
PAINT MONO (-3740 2035);
FORCEPROP 0 LASTPIN (-3750 1925) $PN DA50
J 0
(-3740 1935);
DISPLAY 0.489362 (-3740 1935);
PAINT MONO (-3740 1935);
FORCEPROP 0 LASTPIN (-3750 1825) $PN DC50
J 0
(-3740 1835);
DISPLAY 0.489362 (-3740 1835);
PAINT MONO (-3740 1835);
FORCEPROP 0 LASTPIN (-3750 1725) $PN CW50
J 0
(-3740 1735);
DISPLAY 0.489362 (-3740 1735);
PAINT MONO (-3740 1735);
FORCEPROP 0 LASTPIN (-3750 1625) $PN DA47
J 0
(-3740 1635);
DISPLAY 0.489362 (-3740 1635);
PAINT MONO (-3740 1635);
FORCEPROP 0 LASTPIN (-3750 1525) $PN DC47
J 0
(-3740 1535);
DISPLAY 0.489362 (-3740 1535);
PAINT MONO (-3740 1535);
FORCEPROP 0 LASTPIN (-3750 1425) $PN CW47
J 0
(-3740 1435);
DISPLAY 0.489362 (-3740 1435);
PAINT MONO (-3740 1435);
FORCEPROP 0 LASTPIN (-3750 1325) $PN DA44
J 0
(-3740 1335);
DISPLAY 0.489362 (-3740 1335);
PAINT MONO (-3740 1335);
FORCEPROP 0 LASTPIN (-3750 1225) $PN DC44
J 0
(-3740 1235);
DISPLAY 0.489362 (-3740 1235);
PAINT MONO (-3740 1235);
FORCEPROP 0 LASTPIN (-3750 1125) $PN CW44
J 0
(-3740 1135);
DISPLAY 0.489362 (-3740 1135);
PAINT MONO (-3740 1135);
FORCEPROP 0 LASTPIN (-3750 1025) $PN DB41
J 0
(-3740 1035);
DISPLAY 0.489362 (-3740 1035);
PAINT MONO (-3740 1035);
FORCEPROP 0 LASTPIN (-3750 925) $PN CY41
J 0
(-3740 935);
DISPLAY 0.489362 (-3740 935);
PAINT MONO (-3740 935);
FORCEPROP 0 LASTPIN (-3750 825) $PN CV41
J 0
(-3740 835);
DISPLAY 0.489362 (-3740 835);
PAINT MONO (-3740 835);
FORCEPROP 1 LAST PART_NUMBER DGA^6000030
J 0
(-6100 2634);
DISPLAY 0.489362 (-6100 2634);
PAINT SKYBLUE (-6100 2634);
FORCEPROP 2 LAST PART_TYPE SMLF
J 0
(-6100 2700);
DISPLAY 1.021277 (-6100 2700);
FORCEPROP 1 LAST MATERIAL IO
J 0
(-6100 2507);
DISPLAY 0.489362 (-6100 2507);
PAINT SKYBLUE (-6100 2507);
FORCEPROP 2 LAST VALUE SOCKET6096_13568-001
J 0
(-6100 2575);
DISPLAY 0.489362 (-6100 2575);
PAINT SKYBLUE (-6100 2575);
FORCEPROP 1 LAST PATH I149
J 0
(-5000 1525);
DISPLAY 0.723404 (-5000 1525);
PAINT GREEN (-5000 1525);
DISPLAY INVISIBLE (-5000 1525);
FORCEPROP 1 LAST CDS_LMAN_SYM_OUTLINE -1100,950,1100,-950
J 0
(-5000 1525);
DISPLAY 0.468085 (-5000 1525);
PAINT GREEN (-5000 1525);
DISPLAY INVISIBLE (-5000 1525);
FORCEPROP 1 LAST NEEDS_NO_SIZE TRUE
J 0
(-5000 1525);
DISPLAY 0.723404 (-5000 1525);
PAINT GREEN (-5000 1525);
DISPLAY INVISIBLE (-5000 1525);
FORCEPROP 2 LAST CDS_LIB pure_quanta
J 0
(-5000 1525);
DISPLAY INVISIBLE (-5000 1525);
FORCEADD OFFPAGE..2
(-1800 2550);
FORCEPROP 2 LAST CDS_LIB standard
J 0
(-1800 2550);
DISPLAY INVISIBLE (-1800 2550);
FORCEPROP 2 LAST PATH I218
J 0
(-1500 2600);
DISPLAY 1.021277 (-1500 2600);
DISPLAY INVISIBLE (-1500 2600);
FORCEPROP 1 LAST OFFPAGE TRUE
J 0
(-1475 2425);
DISPLAY 0.872340 (-1475 2425);
PAINT GREEN (-1475 2425);
DISPLAY INVISIBLE (-1475 2425);
FORCEPROP 1 LAST COMMENT_BODY TRUE
J 0
(-1845 2455);
DISPLAY 0.872340 (-1845 2455);
PAINT GREEN (-1845 2455);
DISPLAY INVISIBLE (-1845 2455);
FORCEADD OFFPAGE..2
(-1800 2500);
FORCEPROP 2 LAST PATH I219
J 0
(-1500 2550);
DISPLAY 1.021277 (-1500 2550);
DISPLAY INVISIBLE (-1500 2550);
FORCEPROP 1 LAST COMMENT_BODY TRUE
J 0
(-1845 2405);
DISPLAY 0.872340 (-1845 2405);
PAINT GREEN (-1845 2405);
DISPLAY INVISIBLE (-1845 2405);
FORCEPROP 1 LAST OFFPAGE TRUE
J 0
(-1475 2375);
DISPLAY 0.872340 (-1475 2375);
PAINT GREEN (-1475 2375);
DISPLAY INVISIBLE (-1475 2375);
FORCEPROP 2 LAST CDS_LIB standard
J 0
(-1800 2500);
DISPLAY INVISIBLE (-1800 2500);
FORCEADD TAP..6
R 2
(-3175 2275);
FORCEPROP 3 LASTPIN (-3225 2275) SIG_NAME P5E_CPU0_P1_TX_DN<0>
J 0
(-3215 2285);
DISPLAY 0.659574 (-3215 2285);
PAINT MONO (-3215 2285);
DISPLAY INVISIBLE (-3215 2285);
FORCEPROP 1 LASTPIN (-3225 2275) BN 0
J 2
(-3173 2283);
DISPLAY 0.489362 (-3173 2283);
PAINT MONO (-3173 2283);
FORCEPROP 2 LAST ROOM RISER1
J 0
(-3675 2325);
DISPLAY 0.829787 (-3675 2325);
PAINT RED (-3675 2325);
DISPLAY INVISIBLE (-3675 2325);
FORCEPROP 1 LAST PATH I220
J 2
(-3173 2275);
DISPLAY 0.872340 (-3173 2275);
PAINT GREEN (-3173 2275);
DISPLAY INVISIBLE (-3173 2275);
FORCEPROP 1 LAST HDL_TAP TRUE
J 2
(-3500 2150);
DISPLAY 0.702128 (-3500 2150);
PAINT GREEN (-3500 2150);
DISPLAY INVISIBLE (-3500 2150);
FORCEPROP 1 LAST BODY_TYPE PLUMBING
J 2
(-3175 2225);
DISPLAY 0.702128 (-3175 2225);
PAINT GREEN (-3175 2225);
DISPLAY INVISIBLE (-3175 2225);
FORCEPROP 2 LAST CDS_LIB mstr_standard
J 0
(-3175 2275);
DISPLAY INVISIBLE (-3175 2275);
FORCEPROP 2 LAST BOM_COST IO_SLOT
J 0
(-3675 2375);
DISPLAY 0.829787 (-3675 2375);
DISPLAY INVISIBLE (-3675 2375);
FORCEADD TAP..6
R 2
(-3175 2175);
FORCEPROP 3 LASTPIN (-3225 2175) SIG_NAME P5E_CPU0_P1_TX_DN<1>
J 0
(-3215 2185);
DISPLAY 0.659574 (-3215 2185);
PAINT MONO (-3215 2185);
DISPLAY INVISIBLE (-3215 2185);
FORCEPROP 1 LASTPIN (-3225 2175) BN 1
J 2
(-3173 2183);
DISPLAY 0.489362 (-3173 2183);
PAINT MONO (-3173 2183);
FORCEPROP 2 LAST ROOM RISER1
J 0
(-3675 2225);
DISPLAY 0.829787 (-3675 2225);
PAINT RED (-3675 2225);
DISPLAY INVISIBLE (-3675 2225);
FORCEPROP 1 LAST PATH I221
J 2
(-3173 2175);
DISPLAY 0.872340 (-3173 2175);
PAINT GREEN (-3173 2175);
DISPLAY INVISIBLE (-3173 2175);
FORCEPROP 1 LAST HDL_TAP TRUE
J 2
(-3500 2050);
DISPLAY 0.702128 (-3500 2050);
PAINT GREEN (-3500 2050);
DISPLAY INVISIBLE (-3500 2050);
FORCEPROP 1 LAST BODY_TYPE PLUMBING
J 2
(-3175 2125);
DISPLAY 0.702128 (-3175 2125);
PAINT GREEN (-3175 2125);
DISPLAY INVISIBLE (-3175 2125);
FORCEPROP 2 LAST BOM_COST IO_SLOT
J 0
(-3675 2275);
DISPLAY 0.829787 (-3675 2275);
DISPLAY INVISIBLE (-3675 2275);
FORCEPROP 2 LAST CDS_LIB mstr_standard
J 0
(-3175 2175);
DISPLAY INVISIBLE (-3175 2175);
FORCEADD TAP..6
R 2
(-3325 2225);
FORCEPROP 3 LASTPIN (-3375 2225) SIG_NAME P5E_CPU0_P1_TX_DP<1>
J 0
(-3365 2235);
DISPLAY 0.659574 (-3365 2235);
PAINT MONO (-3365 2235);
DISPLAY INVISIBLE (-3365 2235);
FORCEPROP 1 LASTPIN (-3375 2225) BN 1
J 2
(-3323 2233);
DISPLAY 0.489362 (-3323 2233);
PAINT MONO (-3323 2233);
FORCEPROP 2 LAST ROOM RISER1
J 0
(-3825 2275);
DISPLAY 0.829787 (-3825 2275);
PAINT RED (-3825 2275);
DISPLAY INVISIBLE (-3825 2275);
FORCEPROP 1 LAST PATH I222
J 2
(-3323 2225);
DISPLAY 0.872340 (-3323 2225);
PAINT GREEN (-3323 2225);
DISPLAY INVISIBLE (-3323 2225);
FORCEPROP 1 LAST HDL_TAP TRUE
J 2
(-3650 2100);
DISPLAY 0.702128 (-3650 2100);
PAINT GREEN (-3650 2100);
DISPLAY INVISIBLE (-3650 2100);
FORCEPROP 1 LAST BODY_TYPE PLUMBING
J 2
(-3325 2175);
DISPLAY 0.702128 (-3325 2175);
PAINT GREEN (-3325 2175);
DISPLAY INVISIBLE (-3325 2175);
FORCEPROP 2 LAST BOM_COST IO_SLOT
J 0
(-3825 2325);
DISPLAY 0.829787 (-3825 2325);
DISPLAY INVISIBLE (-3825 2325);
FORCEPROP 2 LAST CDS_LIB mstr_standard
J 0
(-3325 2225);
DISPLAY INVISIBLE (-3325 2225);
FORCEADD TAP..6
R 2
(-3325 2325);
FORCEPROP 3 LASTPIN (-3375 2325) SIG_NAME P5E_CPU0_P1_TX_DP<0>
J 0
(-3365 2335);
DISPLAY 0.659574 (-3365 2335);
PAINT MONO (-3365 2335);
DISPLAY INVISIBLE (-3365 2335);
FORCEPROP 1 LASTPIN (-3375 2325) BN 0
J 2
(-3323 2333);
DISPLAY 0.489362 (-3323 2333);
PAINT MONO (-3323 2333);
FORCEPROP 2 LAST ROOM RISER1
J 0
(-3825 2375);
DISPLAY 0.829787 (-3825 2375);
PAINT RED (-3825 2375);
DISPLAY INVISIBLE (-3825 2375);
FORCEPROP 1 LAST PATH I223
J 2
(-3323 2325);
DISPLAY 0.872340 (-3323 2325);
PAINT GREEN (-3323 2325);
DISPLAY INVISIBLE (-3323 2325);
FORCEPROP 1 LAST HDL_TAP TRUE
J 2
(-3650 2200);
DISPLAY 0.702128 (-3650 2200);
PAINT GREEN (-3650 2200);
DISPLAY INVISIBLE (-3650 2200);
FORCEPROP 1 LAST BODY_TYPE PLUMBING
J 2
(-3325 2275);
DISPLAY 0.702128 (-3325 2275);
PAINT GREEN (-3325 2275);
DISPLAY INVISIBLE (-3325 2275);
FORCEPROP 2 LAST BOM_COST IO_SLOT
J 0
(-3825 2425);
DISPLAY 0.829787 (-3825 2425);
DISPLAY INVISIBLE (-3825 2425);
FORCEPROP 2 LAST CDS_LIB mstr_standard
J 0
(-3325 2325);
DISPLAY INVISIBLE (-3325 2325);
FORCEADD TAP..6
R 2
(-3325 2125);
FORCEPROP 3 LASTPIN (-3375 2125) SIG_NAME P5E_CPU0_P1_TX_DP<2>
J 0
(-3365 2135);
DISPLAY 0.659574 (-3365 2135);
PAINT MONO (-3365 2135);
DISPLAY INVISIBLE (-3365 2135);
FORCEPROP 1 LASTPIN (-3375 2125) BN 2
J 2
(-3323 2133);
DISPLAY 0.489362 (-3323 2133);
PAINT MONO (-3323 2133);
FORCEPROP 2 LAST ROOM RISER1
J 0
(-3825 2175);
DISPLAY 0.829787 (-3825 2175);
PAINT RED (-3825 2175);
DISPLAY INVISIBLE (-3825 2175);
FORCEPROP 1 LAST PATH I224
J 2
(-3323 2125);
DISPLAY 0.872340 (-3323 2125);
PAINT GREEN (-3323 2125);
DISPLAY INVISIBLE (-3323 2125);
FORCEPROP 1 LAST HDL_TAP TRUE
J 2
(-3650 2000);
DISPLAY 0.702128 (-3650 2000);
PAINT GREEN (-3650 2000);
DISPLAY INVISIBLE (-3650 2000);
FORCEPROP 1 LAST BODY_TYPE PLUMBING
J 2
(-3325 2075);
DISPLAY 0.702128 (-3325 2075);
PAINT GREEN (-3325 2075);
DISPLAY INVISIBLE (-3325 2075);
FORCEPROP 2 LAST BOM_COST IO_SLOT
J 0
(-3825 2225);
DISPLAY 0.829787 (-3825 2225);
DISPLAY INVISIBLE (-3825 2225);
FORCEPROP 2 LAST CDS_LIB standard
J 0
(-3325 2125);
DISPLAY INVISIBLE (-3325 2125);
FORCEADD TAP..6
R 2
(-3175 2075);
FORCEPROP 3 LASTPIN (-3225 2075) SIG_NAME P5E_CPU0_P1_TX_DN<2>
J 0
(-3215 2085);
DISPLAY 0.659574 (-3215 2085);
PAINT MONO (-3215 2085);
DISPLAY INVISIBLE (-3215 2085);
FORCEPROP 1 LASTPIN (-3225 2075) BN 2
J 2
(-3173 2083);
DISPLAY 0.489362 (-3173 2083);
PAINT MONO (-3173 2083);
FORCEPROP 2 LAST ROOM RISER1
J 0
(-3675 2125);
DISPLAY 0.829787 (-3675 2125);
PAINT RED (-3675 2125);
DISPLAY INVISIBLE (-3675 2125);
FORCEPROP 1 LAST PATH I225
J 2
(-3173 2075);
DISPLAY 0.872340 (-3173 2075);
PAINT GREEN (-3173 2075);
DISPLAY INVISIBLE (-3173 2075);
FORCEPROP 1 LAST HDL_TAP TRUE
J 2
(-3500 1950);
DISPLAY 0.702128 (-3500 1950);
PAINT GREEN (-3500 1950);
DISPLAY INVISIBLE (-3500 1950);
FORCEPROP 1 LAST BODY_TYPE PLUMBING
J 2
(-3175 2025);
DISPLAY 0.702128 (-3175 2025);
PAINT GREEN (-3175 2025);
DISPLAY INVISIBLE (-3175 2025);
FORCEPROP 2 LAST BOM_COST IO_SLOT
J 0
(-3675 2175);
DISPLAY 0.829787 (-3675 2175);
DISPLAY INVISIBLE (-3675 2175);
FORCEPROP 2 LAST CDS_LIB standard
J 0
(-3175 2075);
DISPLAY INVISIBLE (-3175 2075);
FORCEADD TAP..6
R 2
(-3175 1875);
FORCEPROP 3 LASTPIN (-3225 1875) SIG_NAME P5E_CPU0_P1_TX_DN<4>
J 0
(-3215 1885);
DISPLAY 0.659574 (-3215 1885);
PAINT MONO (-3215 1885);
DISPLAY INVISIBLE (-3215 1885);
FORCEPROP 1 LASTPIN (-3225 1875) BN 4
J 2
(-3173 1883);
DISPLAY 0.489362 (-3173 1883);
PAINT MONO (-3173 1883);
FORCEPROP 2 LAST ROOM RISER1
J 0
(-3675 1925);
DISPLAY 0.829787 (-3675 1925);
PAINT RED (-3675 1925);
DISPLAY INVISIBLE (-3675 1925);
FORCEPROP 1 LAST PATH I226
J 2
(-3173 1875);
DISPLAY 0.872340 (-3173 1875);
PAINT GREEN (-3173 1875);
DISPLAY INVISIBLE (-3173 1875);
FORCEPROP 1 LAST HDL_TAP TRUE
J 2
(-3500 1750);
DISPLAY 0.702128 (-3500 1750);
PAINT GREEN (-3500 1750);
DISPLAY INVISIBLE (-3500 1750);
FORCEPROP 1 LAST BODY_TYPE PLUMBING
J 2
(-3175 1825);
DISPLAY 0.702128 (-3175 1825);
PAINT GREEN (-3175 1825);
DISPLAY INVISIBLE (-3175 1825);
FORCEPROP 2 LAST BOM_COST IO_SLOT
J 0
(-3675 1975);
DISPLAY 0.829787 (-3675 1975);
DISPLAY INVISIBLE (-3675 1975);
FORCEPROP 2 LAST CDS_LIB standard
J 0
(-3175 1875);
DISPLAY INVISIBLE (-3175 1875);
FORCEADD TAP..6
R 2
(-3175 1975);
FORCEPROP 3 LASTPIN (-3225 1975) SIG_NAME P5E_CPU0_P1_TX_DN<3>
J 0
(-3215 1985);
DISPLAY 0.659574 (-3215 1985);
PAINT MONO (-3215 1985);
DISPLAY INVISIBLE (-3215 1985);
FORCEPROP 1 LASTPIN (-3225 1975) BN 3
J 2
(-3173 1983);
DISPLAY 0.489362 (-3173 1983);
PAINT MONO (-3173 1983);
FORCEPROP 2 LAST ROOM RISER1
J 0
(-3675 2025);
DISPLAY 0.829787 (-3675 2025);
PAINT RED (-3675 2025);
DISPLAY INVISIBLE (-3675 2025);
FORCEPROP 1 LAST PATH I227
J 2
(-3173 1975);
DISPLAY 0.872340 (-3173 1975);
PAINT GREEN (-3173 1975);
DISPLAY INVISIBLE (-3173 1975);
FORCEPROP 1 LAST HDL_TAP TRUE
J 2
(-3500 1850);
DISPLAY 0.702128 (-3500 1850);
PAINT GREEN (-3500 1850);
DISPLAY INVISIBLE (-3500 1850);
FORCEPROP 1 LAST BODY_TYPE PLUMBING
J 2
(-3175 1925);
DISPLAY 0.702128 (-3175 1925);
PAINT GREEN (-3175 1925);
DISPLAY INVISIBLE (-3175 1925);
FORCEPROP 2 LAST BOM_COST IO_SLOT
J 0
(-3675 2075);
DISPLAY 0.829787 (-3675 2075);
DISPLAY INVISIBLE (-3675 2075);
FORCEPROP 2 LAST CDS_LIB standard
J 0
(-3175 1975);
DISPLAY INVISIBLE (-3175 1975);
FORCEADD TAP..6
R 2
(-3325 2025);
FORCEPROP 3 LASTPIN (-3375 2025) SIG_NAME P5E_CPU0_P1_TX_DP<3>
J 0
(-3365 2035);
DISPLAY 0.659574 (-3365 2035);
PAINT MONO (-3365 2035);
DISPLAY INVISIBLE (-3365 2035);
FORCEPROP 1 LASTPIN (-3375 2025) BN 3
J 2
(-3323 2033);
DISPLAY 0.489362 (-3323 2033);
PAINT MONO (-3323 2033);
FORCEPROP 2 LAST ROOM RISER1
J 0
(-3825 2075);
DISPLAY 0.829787 (-3825 2075);
PAINT RED (-3825 2075);
DISPLAY INVISIBLE (-3825 2075);
FORCEPROP 1 LAST PATH I228
J 2
(-3323 2025);
DISPLAY 0.872340 (-3323 2025);
PAINT GREEN (-3323 2025);
DISPLAY INVISIBLE (-3323 2025);
FORCEPROP 1 LAST HDL_TAP TRUE
J 2
(-3650 1900);
DISPLAY 0.702128 (-3650 1900);
PAINT GREEN (-3650 1900);
DISPLAY INVISIBLE (-3650 1900);
FORCEPROP 1 LAST BODY_TYPE PLUMBING
J 2
(-3325 1975);
DISPLAY 0.702128 (-3325 1975);
PAINT GREEN (-3325 1975);
DISPLAY INVISIBLE (-3325 1975);
FORCEPROP 2 LAST BOM_COST IO_SLOT
J 0
(-3825 2125);
DISPLAY 0.829787 (-3825 2125);
DISPLAY INVISIBLE (-3825 2125);
FORCEPROP 2 LAST CDS_LIB standard
J 0
(-3325 2025);
DISPLAY INVISIBLE (-3325 2025);
FORCEADD TAP..6
R 2
(-3325 1925);
FORCEPROP 3 LASTPIN (-3375 1925) SIG_NAME P5E_CPU0_P1_TX_DP<4>
J 0
(-3365 1935);
DISPLAY 0.659574 (-3365 1935);
PAINT MONO (-3365 1935);
DISPLAY INVISIBLE (-3365 1935);
FORCEPROP 1 LASTPIN (-3375 1925) BN 4
J 2
(-3323 1933);
DISPLAY 0.489362 (-3323 1933);
PAINT MONO (-3323 1933);
FORCEPROP 2 LAST ROOM RISER1
J 0
(-3825 1975);
DISPLAY 0.829787 (-3825 1975);
PAINT RED (-3825 1975);
DISPLAY INVISIBLE (-3825 1975);
FORCEPROP 1 LAST PATH I229
J 2
(-3323 1925);
DISPLAY 0.872340 (-3323 1925);
PAINT GREEN (-3323 1925);
DISPLAY INVISIBLE (-3323 1925);
FORCEPROP 1 LAST HDL_TAP TRUE
J 2
(-3650 1800);
DISPLAY 0.702128 (-3650 1800);
PAINT GREEN (-3650 1800);
DISPLAY INVISIBLE (-3650 1800);
FORCEPROP 1 LAST BODY_TYPE PLUMBING
J 2
(-3325 1875);
DISPLAY 0.702128 (-3325 1875);
PAINT GREEN (-3325 1875);
DISPLAY INVISIBLE (-3325 1875);
FORCEPROP 2 LAST BOM_COST IO_SLOT
J 0
(-3825 2025);
DISPLAY 0.829787 (-3825 2025);
DISPLAY INVISIBLE (-3825 2025);
FORCEPROP 2 LAST CDS_LIB standard
J 0
(-3325 1925);
DISPLAY INVISIBLE (-3325 1925);
FORCEADD TAP..6
R 2
(-3175 1775);
FORCEPROP 3 LASTPIN (-3225 1775) SIG_NAME P5E_CPU0_P1_TX_DN<5>
J 0
(-3215 1785);
DISPLAY 0.659574 (-3215 1785);
PAINT MONO (-3215 1785);
DISPLAY INVISIBLE (-3215 1785);
FORCEPROP 1 LASTPIN (-3225 1775) BN 5
J 2
(-3173 1783);
DISPLAY 0.489362 (-3173 1783);
PAINT MONO (-3173 1783);
FORCEPROP 2 LAST ROOM RISER1
J 0
(-3675 1825);
DISPLAY 0.829787 (-3675 1825);
PAINT RED (-3675 1825);
DISPLAY INVISIBLE (-3675 1825);
FORCEPROP 1 LAST PATH I230
J 2
(-3173 1775);
DISPLAY 0.872340 (-3173 1775);
PAINT GREEN (-3173 1775);
DISPLAY INVISIBLE (-3173 1775);
FORCEPROP 1 LAST HDL_TAP TRUE
J 2
(-3500 1650);
DISPLAY 0.702128 (-3500 1650);
PAINT GREEN (-3500 1650);
DISPLAY INVISIBLE (-3500 1650);
FORCEPROP 1 LAST BODY_TYPE PLUMBING
J 2
(-3175 1725);
DISPLAY 0.702128 (-3175 1725);
PAINT GREEN (-3175 1725);
DISPLAY INVISIBLE (-3175 1725);
FORCEPROP 2 LAST BOM_COST IO_SLOT
J 0
(-3675 1875);
DISPLAY 0.829787 (-3675 1875);
DISPLAY INVISIBLE (-3675 1875);
FORCEPROP 2 LAST CDS_LIB standard
J 0
(-3175 1775);
DISPLAY INVISIBLE (-3175 1775);
FORCEADD TAP..6
R 2
(-3175 1675);
FORCEPROP 3 LASTPIN (-3225 1675) SIG_NAME P5E_CPU0_P1_TX_DN<6>
J 0
(-3215 1685);
DISPLAY 0.659574 (-3215 1685);
PAINT MONO (-3215 1685);
DISPLAY INVISIBLE (-3215 1685);
FORCEPROP 1 LASTPIN (-3225 1675) BN 6
J 2
(-3173 1683);
DISPLAY 0.489362 (-3173 1683);
PAINT MONO (-3173 1683);
FORCEPROP 2 LAST ROOM RISER1
J 0
(-3675 1725);
DISPLAY 0.829787 (-3675 1725);
PAINT RED (-3675 1725);
DISPLAY INVISIBLE (-3675 1725);
FORCEPROP 1 LAST PATH I231
J 2
(-3173 1675);
DISPLAY 0.872340 (-3173 1675);
PAINT GREEN (-3173 1675);
DISPLAY INVISIBLE (-3173 1675);
FORCEPROP 1 LAST HDL_TAP TRUE
J 2
(-3500 1550);
DISPLAY 0.702128 (-3500 1550);
PAINT GREEN (-3500 1550);
DISPLAY INVISIBLE (-3500 1550);
FORCEPROP 1 LAST BODY_TYPE PLUMBING
J 2
(-3175 1625);
DISPLAY 0.702128 (-3175 1625);
PAINT GREEN (-3175 1625);
DISPLAY INVISIBLE (-3175 1625);
FORCEPROP 2 LAST BOM_COST IO_SLOT
J 0
(-3675 1775);
DISPLAY 0.829787 (-3675 1775);
DISPLAY INVISIBLE (-3675 1775);
FORCEPROP 2 LAST CDS_LIB standard
J 0
(-3175 1675);
DISPLAY INVISIBLE (-3175 1675);
FORCEADD TAP..6
R 2
(-3325 1725);
FORCEPROP 3 LASTPIN (-3375 1725) SIG_NAME P5E_CPU0_P1_TX_DP<6>
J 0
(-3365 1735);
DISPLAY 0.659574 (-3365 1735);
PAINT MONO (-3365 1735);
DISPLAY INVISIBLE (-3365 1735);
FORCEPROP 1 LASTPIN (-3375 1725) BN 6
J 2
(-3323 1733);
DISPLAY 0.489362 (-3323 1733);
PAINT MONO (-3323 1733);
FORCEPROP 2 LAST ROOM RISER1
J 0
(-3825 1775);
DISPLAY 0.829787 (-3825 1775);
PAINT RED (-3825 1775);
DISPLAY INVISIBLE (-3825 1775);
FORCEPROP 1 LAST PATH I232
J 2
(-3323 1725);
DISPLAY 0.872340 (-3323 1725);
PAINT GREEN (-3323 1725);
DISPLAY INVISIBLE (-3323 1725);
FORCEPROP 1 LAST HDL_TAP TRUE
J 2
(-3650 1600);
DISPLAY 0.702128 (-3650 1600);
PAINT GREEN (-3650 1600);
DISPLAY INVISIBLE (-3650 1600);
FORCEPROP 1 LAST BODY_TYPE PLUMBING
J 2
(-3325 1675);
DISPLAY 0.702128 (-3325 1675);
PAINT GREEN (-3325 1675);
DISPLAY INVISIBLE (-3325 1675);
FORCEPROP 2 LAST BOM_COST IO_SLOT
J 0
(-3825 1825);
DISPLAY 0.829787 (-3825 1825);
DISPLAY INVISIBLE (-3825 1825);
FORCEPROP 2 LAST CDS_LIB standard
J 0
(-3325 1725);
DISPLAY INVISIBLE (-3325 1725);
FORCEADD TAP..6
R 2
(-3325 1825);
FORCEPROP 3 LASTPIN (-3375 1825) SIG_NAME P5E_CPU0_P1_TX_DP<5>
J 0
(-3365 1835);
DISPLAY 0.659574 (-3365 1835);
PAINT MONO (-3365 1835);
DISPLAY INVISIBLE (-3365 1835);
FORCEPROP 1 LASTPIN (-3375 1825) BN 5
J 2
(-3323 1833);
DISPLAY 0.489362 (-3323 1833);
PAINT MONO (-3323 1833);
FORCEPROP 2 LAST ROOM RISER1
J 0
(-3825 1875);
DISPLAY 0.829787 (-3825 1875);
PAINT RED (-3825 1875);
DISPLAY INVISIBLE (-3825 1875);
FORCEPROP 1 LAST PATH I233
J 2
(-3323 1825);
DISPLAY 0.872340 (-3323 1825);
PAINT GREEN (-3323 1825);
DISPLAY INVISIBLE (-3323 1825);
FORCEPROP 1 LAST HDL_TAP TRUE
J 2
(-3650 1700);
DISPLAY 0.702128 (-3650 1700);
PAINT GREEN (-3650 1700);
DISPLAY INVISIBLE (-3650 1700);
FORCEPROP 1 LAST BODY_TYPE PLUMBING
J 2
(-3325 1775);
DISPLAY 0.702128 (-3325 1775);
PAINT GREEN (-3325 1775);
DISPLAY INVISIBLE (-3325 1775);
FORCEPROP 2 LAST BOM_COST IO_SLOT
J 0
(-3825 1925);
DISPLAY 0.829787 (-3825 1925);
DISPLAY INVISIBLE (-3825 1925);
FORCEPROP 2 LAST CDS_LIB standard
J 0
(-3325 1825);
DISPLAY INVISIBLE (-3325 1825);
FORCEADD TAP..6
R 2
(-3325 1625);
FORCEPROP 3 LASTPIN (-3375 1625) SIG_NAME P5E_CPU0_P1_TX_DP<7>
J 0
(-3365 1635);
DISPLAY 0.659574 (-3365 1635);
PAINT MONO (-3365 1635);
DISPLAY INVISIBLE (-3365 1635);
FORCEPROP 1 LASTPIN (-3375 1625) BN 7
J 2
(-3323 1633);
DISPLAY 0.489362 (-3323 1633);
PAINT MONO (-3323 1633);
FORCEPROP 2 LAST ROOM RISER1
J 0
(-3825 1675);
DISPLAY 0.829787 (-3825 1675);
PAINT RED (-3825 1675);
DISPLAY INVISIBLE (-3825 1675);
FORCEPROP 1 LAST PATH I234
J 2
(-3323 1625);
DISPLAY 0.872340 (-3323 1625);
PAINT GREEN (-3323 1625);
DISPLAY INVISIBLE (-3323 1625);
FORCEPROP 1 LAST HDL_TAP TRUE
J 2
(-3650 1500);
DISPLAY 0.702128 (-3650 1500);
PAINT GREEN (-3650 1500);
DISPLAY INVISIBLE (-3650 1500);
FORCEPROP 1 LAST BODY_TYPE PLUMBING
J 2
(-3325 1575);
DISPLAY 0.702128 (-3325 1575);
PAINT GREEN (-3325 1575);
DISPLAY INVISIBLE (-3325 1575);
FORCEPROP 2 LAST BOM_COST IO_SLOT
J 0
(-3825 1725);
DISPLAY 0.829787 (-3825 1725);
DISPLAY INVISIBLE (-3825 1725);
FORCEPROP 2 LAST CDS_LIB standard
J 0
(-3325 1625);
DISPLAY INVISIBLE (-3325 1625);
FORCEADD TAP..6
R 2
(-3175 1575);
FORCEPROP 3 LASTPIN (-3225 1575) SIG_NAME P5E_CPU0_P1_TX_DN<7>
J 0
(-3215 1585);
DISPLAY 0.659574 (-3215 1585);
PAINT MONO (-3215 1585);
DISPLAY INVISIBLE (-3215 1585);
FORCEPROP 1 LASTPIN (-3225 1575) BN 7
J 2
(-3173 1583);
DISPLAY 0.489362 (-3173 1583);
PAINT MONO (-3173 1583);
FORCEPROP 2 LAST ROOM RISER1
J 0
(-3675 1625);
DISPLAY 0.829787 (-3675 1625);
PAINT RED (-3675 1625);
DISPLAY INVISIBLE (-3675 1625);
FORCEPROP 1 LAST PATH I235
J 2
(-3173 1575);
DISPLAY 0.872340 (-3173 1575);
PAINT GREEN (-3173 1575);
DISPLAY INVISIBLE (-3173 1575);
FORCEPROP 1 LAST HDL_TAP TRUE
J 2
(-3500 1450);
DISPLAY 0.702128 (-3500 1450);
PAINT GREEN (-3500 1450);
DISPLAY INVISIBLE (-3500 1450);
FORCEPROP 1 LAST BODY_TYPE PLUMBING
J 2
(-3175 1525);
DISPLAY 0.702128 (-3175 1525);
PAINT GREEN (-3175 1525);
DISPLAY INVISIBLE (-3175 1525);
FORCEPROP 2 LAST BOM_COST IO_SLOT
J 0
(-3675 1675);
DISPLAY 0.829787 (-3675 1675);
DISPLAY INVISIBLE (-3675 1675);
FORCEPROP 2 LAST CDS_LIB standard
J 0
(-3175 1575);
DISPLAY INVISIBLE (-3175 1575);
FORCEADD TAP..6
R 2
(-3175 1375);
FORCEPROP 3 LASTPIN (-3225 1375) SIG_NAME P5E_CPU0_P1_TX_DN<9>
J 0
(-3215 1385);
DISPLAY 0.659574 (-3215 1385);
PAINT MONO (-3215 1385);
DISPLAY INVISIBLE (-3215 1385);
FORCEPROP 1 LASTPIN (-3225 1375) BN 9
J 2
(-3173 1383);
DISPLAY 0.489362 (-3173 1383);
PAINT MONO (-3173 1383);
FORCEPROP 2 LAST ROOM RISER1
J 0
(-3675 1425);
DISPLAY 0.829787 (-3675 1425);
PAINT RED (-3675 1425);
DISPLAY INVISIBLE (-3675 1425);
FORCEPROP 1 LAST PATH I236
J 2
(-3173 1375);
DISPLAY 0.872340 (-3173 1375);
PAINT GREEN (-3173 1375);
DISPLAY INVISIBLE (-3173 1375);
FORCEPROP 1 LAST HDL_TAP TRUE
J 2
(-3500 1250);
DISPLAY 0.702128 (-3500 1250);
PAINT GREEN (-3500 1250);
DISPLAY INVISIBLE (-3500 1250);
FORCEPROP 1 LAST BODY_TYPE PLUMBING
J 2
(-3175 1325);
DISPLAY 0.702128 (-3175 1325);
PAINT GREEN (-3175 1325);
DISPLAY INVISIBLE (-3175 1325);
FORCEPROP 2 LAST BOM_COST IO_SLOT
J 0
(-3675 1475);
DISPLAY 0.829787 (-3675 1475);
DISPLAY INVISIBLE (-3675 1475);
FORCEPROP 2 LAST CDS_LIB standard
J 0
(-3175 1375);
DISPLAY INVISIBLE (-3175 1375);
FORCEADD TAP..6
R 2
(-3175 1475);
FORCEPROP 3 LASTPIN (-3225 1475) SIG_NAME P5E_CPU0_P1_TX_DN<8>
J 0
(-3215 1485);
DISPLAY 0.659574 (-3215 1485);
PAINT MONO (-3215 1485);
DISPLAY INVISIBLE (-3215 1485);
FORCEPROP 1 LASTPIN (-3225 1475) BN 8
J 2
(-3173 1483);
DISPLAY 0.489362 (-3173 1483);
PAINT MONO (-3173 1483);
FORCEPROP 2 LAST ROOM RISER1
J 0
(-3675 1525);
DISPLAY 0.829787 (-3675 1525);
PAINT RED (-3675 1525);
DISPLAY INVISIBLE (-3675 1525);
FORCEPROP 1 LAST PATH I237
J 2
(-3173 1475);
DISPLAY 0.872340 (-3173 1475);
PAINT GREEN (-3173 1475);
DISPLAY INVISIBLE (-3173 1475);
FORCEPROP 1 LAST HDL_TAP TRUE
J 2
(-3500 1350);
DISPLAY 0.702128 (-3500 1350);
PAINT GREEN (-3500 1350);
DISPLAY INVISIBLE (-3500 1350);
FORCEPROP 1 LAST BODY_TYPE PLUMBING
J 2
(-3175 1425);
DISPLAY 0.702128 (-3175 1425);
PAINT GREEN (-3175 1425);
DISPLAY INVISIBLE (-3175 1425);
FORCEPROP 2 LAST BOM_COST IO_SLOT
J 0
(-3675 1575);
DISPLAY 0.829787 (-3675 1575);
DISPLAY INVISIBLE (-3675 1575);
FORCEPROP 2 LAST CDS_LIB standard
J 0
(-3175 1475);
DISPLAY INVISIBLE (-3175 1475);
FORCEADD TAP..6
R 2
(-3325 1525);
FORCEPROP 3 LASTPIN (-3375 1525) SIG_NAME P5E_CPU0_P1_TX_DP<8>
J 0
(-3365 1535);
DISPLAY 0.659574 (-3365 1535);
PAINT MONO (-3365 1535);
DISPLAY INVISIBLE (-3365 1535);
FORCEPROP 1 LASTPIN (-3375 1525) BN 8
J 2
(-3323 1533);
DISPLAY 0.489362 (-3323 1533);
PAINT MONO (-3323 1533);
FORCEPROP 2 LAST ROOM RISER1
J 0
(-3825 1575);
DISPLAY 0.829787 (-3825 1575);
PAINT RED (-3825 1575);
DISPLAY INVISIBLE (-3825 1575);
FORCEPROP 1 LAST PATH I238
J 2
(-3323 1525);
DISPLAY 0.872340 (-3323 1525);
PAINT GREEN (-3323 1525);
DISPLAY INVISIBLE (-3323 1525);
FORCEPROP 1 LAST HDL_TAP TRUE
J 2
(-3650 1400);
DISPLAY 0.702128 (-3650 1400);
PAINT GREEN (-3650 1400);
DISPLAY INVISIBLE (-3650 1400);
FORCEPROP 1 LAST BODY_TYPE PLUMBING
J 2
(-3325 1475);
DISPLAY 0.702128 (-3325 1475);
PAINT GREEN (-3325 1475);
DISPLAY INVISIBLE (-3325 1475);
FORCEPROP 2 LAST BOM_COST IO_SLOT
J 0
(-3825 1625);
DISPLAY 0.829787 (-3825 1625);
DISPLAY INVISIBLE (-3825 1625);
FORCEPROP 2 LAST CDS_LIB standard
J 0
(-3325 1525);
DISPLAY INVISIBLE (-3325 1525);
FORCEADD TAP..6
R 2
(-3325 1425);
FORCEPROP 3 LASTPIN (-3375 1425) SIG_NAME P5E_CPU0_P1_TX_DP<9>
J 0
(-3365 1435);
DISPLAY 0.659574 (-3365 1435);
PAINT MONO (-3365 1435);
DISPLAY INVISIBLE (-3365 1435);
FORCEPROP 1 LASTPIN (-3375 1425) BN 9
J 2
(-3323 1433);
DISPLAY 0.489362 (-3323 1433);
PAINT MONO (-3323 1433);
FORCEPROP 2 LAST ROOM RISER1
J 0
(-3825 1475);
DISPLAY 0.829787 (-3825 1475);
PAINT RED (-3825 1475);
DISPLAY INVISIBLE (-3825 1475);
FORCEPROP 1 LAST PATH I239
J 2
(-3323 1425);
DISPLAY 0.872340 (-3323 1425);
PAINT GREEN (-3323 1425);
DISPLAY INVISIBLE (-3323 1425);
FORCEPROP 1 LAST HDL_TAP TRUE
J 2
(-3650 1300);
DISPLAY 0.702128 (-3650 1300);
PAINT GREEN (-3650 1300);
DISPLAY INVISIBLE (-3650 1300);
FORCEPROP 1 LAST BODY_TYPE PLUMBING
J 2
(-3325 1375);
DISPLAY 0.702128 (-3325 1375);
PAINT GREEN (-3325 1375);
DISPLAY INVISIBLE (-3325 1375);
FORCEPROP 2 LAST BOM_COST IO_SLOT
J 0
(-3825 1525);
DISPLAY 0.829787 (-3825 1525);
DISPLAY INVISIBLE (-3825 1525);
FORCEPROP 2 LAST CDS_LIB standard
J 0
(-3325 1425);
DISPLAY INVISIBLE (-3325 1425);
FORCEADD TAP..6
R 2
(-3175 1275);
FORCEPROP 3 LASTPIN (-3225 1275) SIG_NAME P5E_CPU0_P1_TX_DN<10>
J 0
(-3215 1285);
DISPLAY 0.659574 (-3215 1285);
PAINT MONO (-3215 1285);
DISPLAY INVISIBLE (-3215 1285);
FORCEPROP 1 LASTPIN (-3225 1275) BN 10
J 2
(-3173 1283);
DISPLAY 0.489362 (-3173 1283);
PAINT MONO (-3173 1283);
FORCEPROP 2 LAST ROOM RISER1
J 0
(-3675 1325);
DISPLAY 0.829787 (-3675 1325);
PAINT RED (-3675 1325);
DISPLAY INVISIBLE (-3675 1325);
FORCEPROP 1 LAST PATH I240
J 2
(-3173 1275);
DISPLAY 0.872340 (-3173 1275);
PAINT GREEN (-3173 1275);
DISPLAY INVISIBLE (-3173 1275);
FORCEPROP 1 LAST HDL_TAP TRUE
J 2
(-3500 1150);
DISPLAY 0.702128 (-3500 1150);
PAINT GREEN (-3500 1150);
DISPLAY INVISIBLE (-3500 1150);
FORCEPROP 1 LAST BODY_TYPE PLUMBING
J 2
(-3175 1225);
DISPLAY 0.702128 (-3175 1225);
PAINT GREEN (-3175 1225);
DISPLAY INVISIBLE (-3175 1225);
FORCEPROP 2 LAST BOM_COST IO_SLOT
J 0
(-3675 1375);
DISPLAY 0.829787 (-3675 1375);
DISPLAY INVISIBLE (-3675 1375);
FORCEPROP 2 LAST CDS_LIB standard
J 0
(-3175 1275);
DISPLAY INVISIBLE (-3175 1275);
FORCEADD TAP..6
R 2
(-3175 1175);
FORCEPROP 3 LASTPIN (-3225 1175) SIG_NAME P5E_CPU0_P1_TX_DN<11>
J 0
(-3215 1185);
DISPLAY 0.659574 (-3215 1185);
PAINT MONO (-3215 1185);
DISPLAY INVISIBLE (-3215 1185);
FORCEPROP 1 LASTPIN (-3225 1175) BN 11
J 2
(-3173 1183);
DISPLAY 0.489362 (-3173 1183);
PAINT MONO (-3173 1183);
FORCEPROP 2 LAST ROOM RISER1
J 0
(-3675 1225);
DISPLAY 0.829787 (-3675 1225);
PAINT RED (-3675 1225);
DISPLAY INVISIBLE (-3675 1225);
FORCEPROP 1 LAST PATH I241
J 2
(-3173 1175);
DISPLAY 0.872340 (-3173 1175);
PAINT GREEN (-3173 1175);
DISPLAY INVISIBLE (-3173 1175);
FORCEPROP 1 LAST HDL_TAP TRUE
J 2
(-3500 1050);
DISPLAY 0.702128 (-3500 1050);
PAINT GREEN (-3500 1050);
DISPLAY INVISIBLE (-3500 1050);
FORCEPROP 1 LAST BODY_TYPE PLUMBING
J 2
(-3175 1125);
DISPLAY 0.702128 (-3175 1125);
PAINT GREEN (-3175 1125);
DISPLAY INVISIBLE (-3175 1125);
FORCEPROP 2 LAST BOM_COST IO_SLOT
J 0
(-3675 1275);
DISPLAY 0.829787 (-3675 1275);
DISPLAY INVISIBLE (-3675 1275);
FORCEPROP 2 LAST CDS_LIB standard
J 0
(-3175 1175);
DISPLAY INVISIBLE (-3175 1175);
FORCEADD TAP..6
R 2
(-3325 1125);
FORCEPROP 3 LASTPIN (-3375 1125) SIG_NAME P5E_CPU0_P1_TX_DP<12>
J 0
(-3365 1135);
DISPLAY 0.659574 (-3365 1135);
PAINT MONO (-3365 1135);
DISPLAY INVISIBLE (-3365 1135);
FORCEPROP 1 LASTPIN (-3375 1125) BN 12
J 2
(-3323 1133);
DISPLAY 0.489362 (-3323 1133);
PAINT MONO (-3323 1133);
FORCEPROP 2 LAST ROOM RISER1
J 0
(-3825 1175);
DISPLAY 0.829787 (-3825 1175);
PAINT RED (-3825 1175);
DISPLAY INVISIBLE (-3825 1175);
FORCEPROP 1 LAST PATH I242
J 2
(-3323 1125);
DISPLAY 0.872340 (-3323 1125);
PAINT GREEN (-3323 1125);
DISPLAY INVISIBLE (-3323 1125);
FORCEPROP 1 LAST HDL_TAP TRUE
J 2
(-3650 1000);
DISPLAY 0.702128 (-3650 1000);
PAINT GREEN (-3650 1000);
DISPLAY INVISIBLE (-3650 1000);
FORCEPROP 1 LAST BODY_TYPE PLUMBING
J 2
(-3325 1075);
DISPLAY 0.702128 (-3325 1075);
PAINT GREEN (-3325 1075);
DISPLAY INVISIBLE (-3325 1075);
FORCEPROP 2 LAST BOM_COST IO_SLOT
J 0
(-3825 1225);
DISPLAY 0.829787 (-3825 1225);
DISPLAY INVISIBLE (-3825 1225);
FORCEPROP 2 LAST CDS_LIB standard
J 0
(-3325 1125);
DISPLAY INVISIBLE (-3325 1125);
FORCEADD TAP..6
R 2
(-3325 1225);
FORCEPROP 3 LASTPIN (-3375 1225) SIG_NAME P5E_CPU0_P1_TX_DP<11>
J 0
(-3365 1235);
DISPLAY 0.659574 (-3365 1235);
PAINT MONO (-3365 1235);
DISPLAY INVISIBLE (-3365 1235);
FORCEPROP 1 LASTPIN (-3375 1225) BN 11
J 2
(-3323 1233);
DISPLAY 0.489362 (-3323 1233);
PAINT MONO (-3323 1233);
FORCEPROP 2 LAST ROOM RISER1
J 0
(-3825 1275);
DISPLAY 0.829787 (-3825 1275);
PAINT RED (-3825 1275);
DISPLAY INVISIBLE (-3825 1275);
FORCEPROP 1 LAST PATH I243
J 2
(-3323 1225);
DISPLAY 0.872340 (-3323 1225);
PAINT GREEN (-3323 1225);
DISPLAY INVISIBLE (-3323 1225);
FORCEPROP 1 LAST HDL_TAP TRUE
J 2
(-3650 1100);
DISPLAY 0.702128 (-3650 1100);
PAINT GREEN (-3650 1100);
DISPLAY INVISIBLE (-3650 1100);
FORCEPROP 1 LAST BODY_TYPE PLUMBING
J 2
(-3325 1175);
DISPLAY 0.702128 (-3325 1175);
PAINT GREEN (-3325 1175);
DISPLAY INVISIBLE (-3325 1175);
FORCEPROP 2 LAST BOM_COST IO_SLOT
J 0
(-3825 1325);
DISPLAY 0.829787 (-3825 1325);
DISPLAY INVISIBLE (-3825 1325);
FORCEPROP 2 LAST CDS_LIB standard
J 0
(-3325 1225);
DISPLAY INVISIBLE (-3325 1225);
FORCEADD TAP..6
R 2
(-3325 1325);
FORCEPROP 3 LASTPIN (-3375 1325) SIG_NAME P5E_CPU0_P1_TX_DP<10>
J 0
(-3365 1335);
DISPLAY 0.659574 (-3365 1335);
PAINT MONO (-3365 1335);
DISPLAY INVISIBLE (-3365 1335);
FORCEPROP 1 LASTPIN (-3375 1325) BN 10
J 2
(-3323 1333);
DISPLAY 0.489362 (-3323 1333);
PAINT MONO (-3323 1333);
FORCEPROP 2 LAST ROOM RISER1
J 0
(-3825 1375);
DISPLAY 0.829787 (-3825 1375);
PAINT RED (-3825 1375);
DISPLAY INVISIBLE (-3825 1375);
FORCEPROP 1 LAST PATH I244
J 2
(-3323 1325);
DISPLAY 0.872340 (-3323 1325);
PAINT GREEN (-3323 1325);
DISPLAY INVISIBLE (-3323 1325);
FORCEPROP 1 LAST HDL_TAP TRUE
J 2
(-3650 1200);
DISPLAY 0.702128 (-3650 1200);
PAINT GREEN (-3650 1200);
DISPLAY INVISIBLE (-3650 1200);
FORCEPROP 1 LAST BODY_TYPE PLUMBING
J 2
(-3325 1275);
DISPLAY 0.702128 (-3325 1275);
PAINT GREEN (-3325 1275);
DISPLAY INVISIBLE (-3325 1275);
FORCEPROP 2 LAST BOM_COST IO_SLOT
J 0
(-3825 1425);
DISPLAY 0.829787 (-3825 1425);
DISPLAY INVISIBLE (-3825 1425);
FORCEPROP 2 LAST CDS_LIB standard
J 0
(-3325 1325);
DISPLAY INVISIBLE (-3325 1325);
FORCEADD TAP..6
R 2
(-3175 975);
FORCEPROP 3 LASTPIN (-3225 975) SIG_NAME P5E_CPU0_P1_TX_DN<13>
J 0
(-3215 985);
DISPLAY 0.659574 (-3215 985);
PAINT MONO (-3215 985);
DISPLAY INVISIBLE (-3215 985);
FORCEPROP 1 LASTPIN (-3225 975) BN 13
J 2
(-3173 983);
DISPLAY 0.489362 (-3173 983);
PAINT MONO (-3173 983);
FORCEPROP 2 LAST ROOM RISER1
J 0
(-3675 1025);
DISPLAY 0.829787 (-3675 1025);
PAINT RED (-3675 1025);
DISPLAY INVISIBLE (-3675 1025);
FORCEPROP 1 LAST PATH I245
J 2
(-3173 975);
DISPLAY 0.872340 (-3173 975);
PAINT GREEN (-3173 975);
DISPLAY INVISIBLE (-3173 975);
FORCEPROP 1 LAST HDL_TAP TRUE
J 2
(-3500 850);
DISPLAY 0.702128 (-3500 850);
PAINT GREEN (-3500 850);
DISPLAY INVISIBLE (-3500 850);
FORCEPROP 1 LAST BODY_TYPE PLUMBING
J 2
(-3175 925);
DISPLAY 0.702128 (-3175 925);
PAINT GREEN (-3175 925);
DISPLAY INVISIBLE (-3175 925);
FORCEPROP 2 LAST BOM_COST IO_SLOT
J 0
(-3675 1075);
DISPLAY 0.829787 (-3675 1075);
DISPLAY INVISIBLE (-3675 1075);
FORCEPROP 2 LAST CDS_LIB standard
J 0
(-3175 975);
DISPLAY INVISIBLE (-3175 975);
FORCEADD TAP..6
R 2
(-3175 1075);
FORCEPROP 3 LASTPIN (-3225 1075) SIG_NAME P5E_CPU0_P1_TX_DN<12>
J 0
(-3215 1085);
DISPLAY 0.659574 (-3215 1085);
PAINT MONO (-3215 1085);
DISPLAY INVISIBLE (-3215 1085);
FORCEPROP 1 LASTPIN (-3225 1075) BN 12
J 2
(-3173 1083);
DISPLAY 0.489362 (-3173 1083);
PAINT MONO (-3173 1083);
FORCEPROP 2 LAST ROOM RISER1
J 0
(-3675 1125);
DISPLAY 0.829787 (-3675 1125);
PAINT RED (-3675 1125);
DISPLAY INVISIBLE (-3675 1125);
FORCEPROP 1 LAST PATH I246
J 2
(-3173 1075);
DISPLAY 0.872340 (-3173 1075);
PAINT GREEN (-3173 1075);
DISPLAY INVISIBLE (-3173 1075);
FORCEPROP 1 LAST HDL_TAP TRUE
J 2
(-3500 950);
DISPLAY 0.702128 (-3500 950);
PAINT GREEN (-3500 950);
DISPLAY INVISIBLE (-3500 950);
FORCEPROP 1 LAST BODY_TYPE PLUMBING
J 2
(-3175 1025);
DISPLAY 0.702128 (-3175 1025);
PAINT GREEN (-3175 1025);
DISPLAY INVISIBLE (-3175 1025);
FORCEPROP 2 LAST BOM_COST IO_SLOT
J 0
(-3675 1175);
DISPLAY 0.829787 (-3675 1175);
DISPLAY INVISIBLE (-3675 1175);
FORCEPROP 2 LAST CDS_LIB standard
J 0
(-3175 1075);
DISPLAY INVISIBLE (-3175 1075);
FORCEADD TAP..6
R 2
(-3175 875);
FORCEPROP 3 LASTPIN (-3225 875) SIG_NAME P5E_CPU0_P1_TX_DN<14>
J 0
(-3215 885);
DISPLAY 0.659574 (-3215 885);
PAINT MONO (-3215 885);
DISPLAY INVISIBLE (-3215 885);
FORCEPROP 1 LASTPIN (-3225 875) BN 14
J 2
(-3173 883);
DISPLAY 0.489362 (-3173 883);
PAINT MONO (-3173 883);
FORCEPROP 2 LAST ROOM RISER1
J 0
(-3675 925);
DISPLAY 0.829787 (-3675 925);
PAINT RED (-3675 925);
DISPLAY INVISIBLE (-3675 925);
FORCEPROP 1 LAST PATH I247
J 2
(-3173 875);
DISPLAY 0.872340 (-3173 875);
PAINT GREEN (-3173 875);
DISPLAY INVISIBLE (-3173 875);
FORCEPROP 1 LAST HDL_TAP TRUE
J 2
(-3500 750);
DISPLAY 0.702128 (-3500 750);
PAINT GREEN (-3500 750);
DISPLAY INVISIBLE (-3500 750);
FORCEPROP 1 LAST BODY_TYPE PLUMBING
J 2
(-3175 825);
DISPLAY 0.702128 (-3175 825);
PAINT GREEN (-3175 825);
DISPLAY INVISIBLE (-3175 825);
FORCEPROP 2 LAST BOM_COST IO_SLOT
J 0
(-3675 975);
DISPLAY 0.829787 (-3675 975);
DISPLAY INVISIBLE (-3675 975);
FORCEPROP 2 LAST CDS_LIB standard
J 0
(-3175 875);
DISPLAY INVISIBLE (-3175 875);
FORCEADD TAP..6
R 2
(-3325 1025);
FORCEPROP 3 LASTPIN (-3375 1025) SIG_NAME P5E_CPU0_P1_TX_DP<13>
J 0
(-3365 1035);
DISPLAY 0.659574 (-3365 1035);
PAINT MONO (-3365 1035);
DISPLAY INVISIBLE (-3365 1035);
FORCEPROP 1 LASTPIN (-3375 1025) BN 13
J 2
(-3323 1033);
DISPLAY 0.489362 (-3323 1033);
PAINT MONO (-3323 1033);
FORCEPROP 2 LAST ROOM RISER1
J 0
(-3825 1075);
DISPLAY 0.829787 (-3825 1075);
PAINT RED (-3825 1075);
DISPLAY INVISIBLE (-3825 1075);
FORCEPROP 1 LAST PATH I248
J 2
(-3323 1025);
DISPLAY 0.872340 (-3323 1025);
PAINT GREEN (-3323 1025);
DISPLAY INVISIBLE (-3323 1025);
FORCEPROP 1 LAST HDL_TAP TRUE
J 2
(-3650 900);
DISPLAY 0.702128 (-3650 900);
PAINT GREEN (-3650 900);
DISPLAY INVISIBLE (-3650 900);
FORCEPROP 1 LAST BODY_TYPE PLUMBING
J 2
(-3325 975);
DISPLAY 0.702128 (-3325 975);
PAINT GREEN (-3325 975);
DISPLAY INVISIBLE (-3325 975);
FORCEPROP 2 LAST BOM_COST IO_SLOT
J 0
(-3825 1125);
DISPLAY 0.829787 (-3825 1125);
DISPLAY INVISIBLE (-3825 1125);
FORCEPROP 2 LAST CDS_LIB standard
J 0
(-3325 1025);
DISPLAY INVISIBLE (-3325 1025);
FORCEADD TAP..6
R 2
(-3325 925);
FORCEPROP 3 LASTPIN (-3375 925) SIG_NAME P5E_CPU0_P1_TX_DP<14>
J 0
(-3365 935);
DISPLAY 0.659574 (-3365 935);
PAINT MONO (-3365 935);
DISPLAY INVISIBLE (-3365 935);
FORCEPROP 1 LASTPIN (-3375 925) BN 14
J 2
(-3323 933);
DISPLAY 0.489362 (-3323 933);
PAINT MONO (-3323 933);
FORCEPROP 2 LAST ROOM RISER1
J 0
(-3825 975);
DISPLAY 0.829787 (-3825 975);
PAINT RED (-3825 975);
DISPLAY INVISIBLE (-3825 975);
FORCEPROP 1 LAST PATH I249
J 2
(-3323 925);
DISPLAY 0.872340 (-3323 925);
PAINT GREEN (-3323 925);
DISPLAY INVISIBLE (-3323 925);
FORCEPROP 1 LAST HDL_TAP TRUE
J 2
(-3650 800);
DISPLAY 0.702128 (-3650 800);
PAINT GREEN (-3650 800);
DISPLAY INVISIBLE (-3650 800);
FORCEPROP 1 LAST BODY_TYPE PLUMBING
J 2
(-3325 875);
DISPLAY 0.702128 (-3325 875);
PAINT GREEN (-3325 875);
DISPLAY INVISIBLE (-3325 875);
FORCEPROP 2 LAST BOM_COST IO_SLOT
J 0
(-3825 1025);
DISPLAY 0.829787 (-3825 1025);
DISPLAY INVISIBLE (-3825 1025);
FORCEPROP 2 LAST CDS_LIB standard
J 0
(-3325 925);
DISPLAY INVISIBLE (-3325 925);
FORCEADD TAP..6
R 2
(-3325 825);
FORCEPROP 3 LASTPIN (-3375 825) SIG_NAME P5E_CPU0_P1_TX_DP<15>
J 0
(-3365 835);
DISPLAY 0.659574 (-3365 835);
PAINT MONO (-3365 835);
DISPLAY INVISIBLE (-3365 835);
FORCEPROP 1 LASTPIN (-3375 825) BN 15
J 2
(-3323 833);
DISPLAY 0.489362 (-3323 833);
PAINT MONO (-3323 833);
FORCEPROP 2 LAST ROOM RISER1
J 0
(-3825 875);
DISPLAY 0.829787 (-3825 875);
PAINT RED (-3825 875);
DISPLAY INVISIBLE (-3825 875);
FORCEPROP 1 LAST PATH I250
J 2
(-3323 825);
DISPLAY 0.872340 (-3323 825);
PAINT GREEN (-3323 825);
DISPLAY INVISIBLE (-3323 825);
FORCEPROP 1 LAST HDL_TAP TRUE
J 2
(-3650 700);
DISPLAY 0.702128 (-3650 700);
PAINT GREEN (-3650 700);
DISPLAY INVISIBLE (-3650 700);
FORCEPROP 1 LAST BODY_TYPE PLUMBING
J 2
(-3325 775);
DISPLAY 0.702128 (-3325 775);
PAINT GREEN (-3325 775);
DISPLAY INVISIBLE (-3325 775);
FORCEPROP 2 LAST BOM_COST IO_SLOT
J 0
(-3825 925);
DISPLAY 0.829787 (-3825 925);
DISPLAY INVISIBLE (-3825 925);
FORCEPROP 2 LAST CDS_LIB standard
J 0
(-3325 825);
DISPLAY INVISIBLE (-3325 825);
FORCEADD TAP..6
R 2
(-3175 775);
FORCEPROP 3 LASTPIN (-3225 775) SIG_NAME P5E_CPU0_P1_TX_DN<15>
J 0
(-3215 785);
DISPLAY 0.659574 (-3215 785);
PAINT MONO (-3215 785);
DISPLAY INVISIBLE (-3215 785);
FORCEPROP 1 LASTPIN (-3225 775) BN 15
J 2
(-3173 783);
DISPLAY 0.489362 (-3173 783);
PAINT MONO (-3173 783);
FORCEPROP 2 LAST ROOM RISER1
J 0
(-3675 825);
DISPLAY 0.829787 (-3675 825);
PAINT RED (-3675 825);
DISPLAY INVISIBLE (-3675 825);
FORCEPROP 1 LAST PATH I251
J 2
(-3173 775);
DISPLAY 0.872340 (-3173 775);
PAINT GREEN (-3173 775);
DISPLAY INVISIBLE (-3173 775);
FORCEPROP 1 LAST HDL_TAP TRUE
J 2
(-3500 650);
DISPLAY 0.702128 (-3500 650);
PAINT GREEN (-3500 650);
DISPLAY INVISIBLE (-3500 650);
FORCEPROP 1 LAST BODY_TYPE PLUMBING
J 2
(-3175 725);
DISPLAY 0.702128 (-3175 725);
PAINT GREEN (-3175 725);
DISPLAY INVISIBLE (-3175 725);
FORCEPROP 2 LAST BOM_COST IO_SLOT
J 0
(-3675 875);
DISPLAY 0.829787 (-3675 875);
DISPLAY INVISIBLE (-3675 875);
FORCEPROP 2 LAST CDS_LIB standard
J 0
(-3175 775);
DISPLAY INVISIBLE (-3175 775);
FORCEADD TAP..6
(-6900 775);
FORCEPROP 3 LASTPIN (-6850 775) SIG_NAME P5E_CPU0_P1_RX_DN<15>
J 0
(-6840 785);
DISPLAY 0.659574 (-6840 785);
PAINT MONO (-6840 785);
DISPLAY INVISIBLE (-6840 785);
FORCEPROP 1 LASTPIN (-6850 775) BN 15
J 0
(-6902 783);
DISPLAY 0.489362 (-6902 783);
PAINT MONO (-6902 783);
FORCEPROP 1 LAST PATH I292
J 0
(-6902 775);
DISPLAY 0.872340 (-6902 775);
PAINT GREEN (-6902 775);
DISPLAY INVISIBLE (-6902 775);
FORCEPROP 1 LAST HDL_TAP TRUE
J 0
(-6575 650);
DISPLAY 0.574468 (-6575 650);
PAINT GREEN (-6575 650);
DISPLAY INVISIBLE (-6575 650);
FORCEPROP 1 LAST BODY_TYPE PLUMBING
J 0
(-6900 725);
DISPLAY 0.574468 (-6900 725);
PAINT GREEN (-6900 725);
DISPLAY INVISIBLE (-6900 725);
FORCEPROP 2 LAST CDS_LIB standard
J 0
(-6900 775);
DISPLAY INVISIBLE (-6900 775);
FORCEADD TAP..6
(-6900 875);
FORCEPROP 3 LASTPIN (-6850 875) SIG_NAME P5E_CPU0_P1_RX_DN<14>
J 0
(-6840 885);
DISPLAY 0.659574 (-6840 885);
PAINT MONO (-6840 885);
DISPLAY INVISIBLE (-6840 885);
FORCEPROP 1 LASTPIN (-6850 875) BN 14
J 0
(-6902 883);
DISPLAY 0.489362 (-6902 883);
PAINT MONO (-6902 883);
FORCEPROP 1 LAST PATH I293
J 0
(-6902 875);
DISPLAY 0.872340 (-6902 875);
PAINT GREEN (-6902 875);
DISPLAY INVISIBLE (-6902 875);
FORCEPROP 1 LAST HDL_TAP TRUE
J 0
(-6575 750);
DISPLAY 0.574468 (-6575 750);
PAINT GREEN (-6575 750);
DISPLAY INVISIBLE (-6575 750);
FORCEPROP 1 LAST BODY_TYPE PLUMBING
J 0
(-6900 825);
DISPLAY 0.574468 (-6900 825);
PAINT GREEN (-6900 825);
DISPLAY INVISIBLE (-6900 825);
FORCEPROP 2 LAST CDS_LIB standard
J 0
(-6900 875);
DISPLAY INVISIBLE (-6900 875);
FORCEADD TAP..6
(-6750 825);
FORCEPROP 3 LASTPIN (-6700 825) SIG_NAME P5E_CPU0_P1_RX_DP<15>
J 0
(-6690 835);
DISPLAY 0.659574 (-6690 835);
PAINT MONO (-6690 835);
DISPLAY INVISIBLE (-6690 835);
FORCEPROP 1 LASTPIN (-6700 825) BN 15
J 0
(-6752 833);
DISPLAY 0.489362 (-6752 833);
PAINT MONO (-6752 833);
FORCEPROP 1 LAST PATH I294
J 0
(-6752 825);
DISPLAY 0.872340 (-6752 825);
PAINT GREEN (-6752 825);
DISPLAY INVISIBLE (-6752 825);
FORCEPROP 1 LAST HDL_TAP TRUE
J 0
(-6425 700);
DISPLAY 0.574468 (-6425 700);
PAINT GREEN (-6425 700);
DISPLAY INVISIBLE (-6425 700);
FORCEPROP 1 LAST BODY_TYPE PLUMBING
J 0
(-6750 775);
DISPLAY 0.574468 (-6750 775);
PAINT GREEN (-6750 775);
DISPLAY INVISIBLE (-6750 775);
FORCEPROP 2 LAST CDS_LIB standard
J 0
(-6750 825);
DISPLAY INVISIBLE (-6750 825);
FORCEADD TAP..6
(-6750 925);
FORCEPROP 3 LASTPIN (-6700 925) SIG_NAME P5E_CPU0_P1_RX_DP<14>
J 0
(-6690 935);
DISPLAY 0.659574 (-6690 935);
PAINT MONO (-6690 935);
DISPLAY INVISIBLE (-6690 935);
FORCEPROP 1 LASTPIN (-6700 925) BN 14
J 0
(-6752 933);
DISPLAY 0.489362 (-6752 933);
PAINT MONO (-6752 933);
FORCEPROP 1 LAST PATH I295
J 0
(-6752 925);
DISPLAY 0.872340 (-6752 925);
PAINT GREEN (-6752 925);
DISPLAY INVISIBLE (-6752 925);
FORCEPROP 1 LAST HDL_TAP TRUE
J 0
(-6425 800);
DISPLAY 0.574468 (-6425 800);
PAINT GREEN (-6425 800);
DISPLAY INVISIBLE (-6425 800);
FORCEPROP 1 LAST BODY_TYPE PLUMBING
J 0
(-6750 875);
DISPLAY 0.574468 (-6750 875);
PAINT GREEN (-6750 875);
DISPLAY INVISIBLE (-6750 875);
FORCEPROP 2 LAST CDS_LIB standard
J 0
(-6750 925);
DISPLAY INVISIBLE (-6750 925);
FORCEADD TAP..6
(-6900 1075);
FORCEPROP 3 LASTPIN (-6850 1075) SIG_NAME P5E_CPU0_P1_RX_DN<12>
J 0
(-6840 1085);
DISPLAY 0.659574 (-6840 1085);
PAINT MONO (-6840 1085);
DISPLAY INVISIBLE (-6840 1085);
FORCEPROP 1 LASTPIN (-6850 1075) BN 12
J 0
(-6902 1083);
DISPLAY 0.489362 (-6902 1083);
PAINT MONO (-6902 1083);
FORCEPROP 1 LAST PATH I296
J 0
(-6902 1075);
DISPLAY 0.872340 (-6902 1075);
PAINT GREEN (-6902 1075);
DISPLAY INVISIBLE (-6902 1075);
FORCEPROP 1 LAST HDL_TAP TRUE
J 0
(-6575 950);
DISPLAY 0.574468 (-6575 950);
PAINT GREEN (-6575 950);
DISPLAY INVISIBLE (-6575 950);
FORCEPROP 1 LAST BODY_TYPE PLUMBING
J 0
(-6900 1025);
DISPLAY 0.574468 (-6900 1025);
PAINT GREEN (-6900 1025);
DISPLAY INVISIBLE (-6900 1025);
FORCEPROP 2 LAST CDS_LIB standard
J 0
(-6900 1075);
DISPLAY INVISIBLE (-6900 1075);
FORCEADD TAP..6
(-6900 975);
FORCEPROP 3 LASTPIN (-6850 975) SIG_NAME P5E_CPU0_P1_RX_DN<13>
J 0
(-6840 985);
DISPLAY 0.659574 (-6840 985);
PAINT MONO (-6840 985);
DISPLAY INVISIBLE (-6840 985);
FORCEPROP 1 LASTPIN (-6850 975) BN 13
J 0
(-6902 983);
DISPLAY 0.489362 (-6902 983);
PAINT MONO (-6902 983);
FORCEPROP 1 LAST PATH I297
J 0
(-6902 975);
DISPLAY 0.872340 (-6902 975);
PAINT GREEN (-6902 975);
DISPLAY INVISIBLE (-6902 975);
FORCEPROP 1 LAST HDL_TAP TRUE
J 0
(-6575 850);
DISPLAY 0.574468 (-6575 850);
PAINT GREEN (-6575 850);
DISPLAY INVISIBLE (-6575 850);
FORCEPROP 1 LAST BODY_TYPE PLUMBING
J 0
(-6900 925);
DISPLAY 0.574468 (-6900 925);
PAINT GREEN (-6900 925);
DISPLAY INVISIBLE (-6900 925);
FORCEPROP 2 LAST CDS_LIB standard
J 0
(-6900 975);
DISPLAY INVISIBLE (-6900 975);
FORCEADD TAP..6
(-6900 1175);
FORCEPROP 3 LASTPIN (-6850 1175) SIG_NAME P5E_CPU0_P1_RX_DN<11>
J 0
(-6840 1185);
DISPLAY 0.659574 (-6840 1185);
PAINT MONO (-6840 1185);
DISPLAY INVISIBLE (-6840 1185);
FORCEPROP 1 LASTPIN (-6850 1175) BN 11
J 0
(-6902 1183);
DISPLAY 0.489362 (-6902 1183);
PAINT MONO (-6902 1183);
FORCEPROP 1 LAST PATH I298
J 0
(-6902 1175);
DISPLAY 0.872340 (-6902 1175);
PAINT GREEN (-6902 1175);
DISPLAY INVISIBLE (-6902 1175);
FORCEPROP 1 LAST HDL_TAP TRUE
J 0
(-6575 1050);
DISPLAY 0.574468 (-6575 1050);
PAINT GREEN (-6575 1050);
DISPLAY INVISIBLE (-6575 1050);
FORCEPROP 1 LAST BODY_TYPE PLUMBING
J 0
(-6900 1125);
DISPLAY 0.574468 (-6900 1125);
PAINT GREEN (-6900 1125);
DISPLAY INVISIBLE (-6900 1125);
FORCEPROP 2 LAST CDS_LIB standard
J 0
(-6900 1175);
DISPLAY INVISIBLE (-6900 1175);
FORCEADD TAP..6
(-6750 1025);
FORCEPROP 3 LASTPIN (-6700 1025) SIG_NAME P5E_CPU0_P1_RX_DP<13>
J 0
(-6690 1035);
DISPLAY 0.659574 (-6690 1035);
PAINT MONO (-6690 1035);
DISPLAY INVISIBLE (-6690 1035);
FORCEPROP 1 LASTPIN (-6700 1025) BN 13
J 0
(-6752 1033);
DISPLAY 0.489362 (-6752 1033);
PAINT MONO (-6752 1033);
FORCEPROP 1 LAST PATH I299
J 0
(-6752 1025);
DISPLAY 0.872340 (-6752 1025);
PAINT GREEN (-6752 1025);
DISPLAY INVISIBLE (-6752 1025);
FORCEPROP 1 LAST HDL_TAP TRUE
J 0
(-6425 900);
DISPLAY 0.574468 (-6425 900);
PAINT GREEN (-6425 900);
DISPLAY INVISIBLE (-6425 900);
FORCEPROP 1 LAST BODY_TYPE PLUMBING
J 0
(-6750 975);
DISPLAY 0.574468 (-6750 975);
PAINT GREEN (-6750 975);
DISPLAY INVISIBLE (-6750 975);
FORCEPROP 2 LAST CDS_LIB standard
J 0
(-6750 1025);
DISPLAY INVISIBLE (-6750 1025);
FORCEADD TAP..6
(-6750 1125);
FORCEPROP 3 LASTPIN (-6700 1125) SIG_NAME P5E_CPU0_P1_RX_DP<12>
J 0
(-6690 1135);
DISPLAY 0.659574 (-6690 1135);
PAINT MONO (-6690 1135);
DISPLAY INVISIBLE (-6690 1135);
FORCEPROP 1 LASTPIN (-6700 1125) BN 12
J 0
(-6752 1133);
DISPLAY 0.489362 (-6752 1133);
PAINT MONO (-6752 1133);
FORCEPROP 1 LAST PATH I300
J 0
(-6752 1125);
DISPLAY 0.872340 (-6752 1125);
PAINT GREEN (-6752 1125);
DISPLAY INVISIBLE (-6752 1125);
FORCEPROP 1 LAST HDL_TAP TRUE
J 0
(-6425 1000);
DISPLAY 0.574468 (-6425 1000);
PAINT GREEN (-6425 1000);
DISPLAY INVISIBLE (-6425 1000);
FORCEPROP 1 LAST BODY_TYPE PLUMBING
J 0
(-6750 1075);
DISPLAY 0.574468 (-6750 1075);
PAINT GREEN (-6750 1075);
DISPLAY INVISIBLE (-6750 1075);
FORCEPROP 2 LAST CDS_LIB standard
J 0
(-6750 1125);
DISPLAY INVISIBLE (-6750 1125);
FORCEADD TAP..6
(-6900 1275);
FORCEPROP 3 LASTPIN (-6850 1275) SIG_NAME P5E_CPU0_P1_RX_DN<10>
J 0
(-6840 1285);
DISPLAY 0.659574 (-6840 1285);
PAINT MONO (-6840 1285);
DISPLAY INVISIBLE (-6840 1285);
FORCEPROP 1 LASTPIN (-6850 1275) BN 10
J 0
(-6902 1283);
DISPLAY 0.489362 (-6902 1283);
PAINT MONO (-6902 1283);
FORCEPROP 1 LAST PATH I301
J 0
(-6902 1275);
DISPLAY 0.872340 (-6902 1275);
PAINT GREEN (-6902 1275);
DISPLAY INVISIBLE (-6902 1275);
FORCEPROP 1 LAST HDL_TAP TRUE
J 0
(-6575 1150);
DISPLAY 0.574468 (-6575 1150);
PAINT GREEN (-6575 1150);
DISPLAY INVISIBLE (-6575 1150);
FORCEPROP 1 LAST BODY_TYPE PLUMBING
J 0
(-6900 1225);
DISPLAY 0.574468 (-6900 1225);
PAINT GREEN (-6900 1225);
DISPLAY INVISIBLE (-6900 1225);
FORCEPROP 2 LAST CDS_LIB standard
J 0
(-6900 1275);
DISPLAY INVISIBLE (-6900 1275);
FORCEADD TAP..6
(-6900 1375);
FORCEPROP 3 LASTPIN (-6850 1375) SIG_NAME P5E_CPU0_P1_RX_DN<9>
J 0
(-6840 1385);
DISPLAY 0.659574 (-6840 1385);
PAINT MONO (-6840 1385);
DISPLAY INVISIBLE (-6840 1385);
FORCEPROP 1 LASTPIN (-6850 1375) BN 9
J 0
(-6902 1383);
DISPLAY 0.489362 (-6902 1383);
PAINT MONO (-6902 1383);
FORCEPROP 1 LAST PATH I302
J 0
(-6902 1375);
DISPLAY 0.872340 (-6902 1375);
PAINT GREEN (-6902 1375);
DISPLAY INVISIBLE (-6902 1375);
FORCEPROP 1 LAST HDL_TAP TRUE
J 0
(-6575 1250);
DISPLAY 0.574468 (-6575 1250);
PAINT GREEN (-6575 1250);
DISPLAY INVISIBLE (-6575 1250);
FORCEPROP 1 LAST BODY_TYPE PLUMBING
J 0
(-6900 1325);
DISPLAY 0.574468 (-6900 1325);
PAINT GREEN (-6900 1325);
DISPLAY INVISIBLE (-6900 1325);
FORCEPROP 2 LAST CDS_LIB standard
J 0
(-6900 1375);
DISPLAY INVISIBLE (-6900 1375);
FORCEADD TAP..6
(-6750 1225);
FORCEPROP 3 LASTPIN (-6700 1225) SIG_NAME P5E_CPU0_P1_RX_DP<11>
J 0
(-6690 1235);
DISPLAY 0.659574 (-6690 1235);
PAINT MONO (-6690 1235);
DISPLAY INVISIBLE (-6690 1235);
FORCEPROP 1 LASTPIN (-6700 1225) BN 11
J 0
(-6752 1233);
DISPLAY 0.489362 (-6752 1233);
PAINT MONO (-6752 1233);
FORCEPROP 1 LAST PATH I303
J 0
(-6752 1225);
DISPLAY 0.872340 (-6752 1225);
PAINT GREEN (-6752 1225);
DISPLAY INVISIBLE (-6752 1225);
FORCEPROP 1 LAST HDL_TAP TRUE
J 0
(-6425 1100);
DISPLAY 0.574468 (-6425 1100);
PAINT GREEN (-6425 1100);
DISPLAY INVISIBLE (-6425 1100);
FORCEPROP 1 LAST BODY_TYPE PLUMBING
J 0
(-6750 1175);
DISPLAY 0.574468 (-6750 1175);
PAINT GREEN (-6750 1175);
DISPLAY INVISIBLE (-6750 1175);
FORCEPROP 2 LAST CDS_LIB standard
J 0
(-6750 1225);
DISPLAY INVISIBLE (-6750 1225);
FORCEADD TAP..6
(-6750 1325);
FORCEPROP 3 LASTPIN (-6700 1325) SIG_NAME P5E_CPU0_P1_RX_DP<10>
J 0
(-6690 1335);
DISPLAY 0.659574 (-6690 1335);
PAINT MONO (-6690 1335);
DISPLAY INVISIBLE (-6690 1335);
FORCEPROP 1 LASTPIN (-6700 1325) BN 10
J 0
(-6752 1333);
DISPLAY 0.489362 (-6752 1333);
PAINT MONO (-6752 1333);
FORCEPROP 1 LAST PATH I304
J 0
(-6752 1325);
DISPLAY 0.872340 (-6752 1325);
PAINT GREEN (-6752 1325);
DISPLAY INVISIBLE (-6752 1325);
FORCEPROP 1 LAST HDL_TAP TRUE
J 0
(-6425 1200);
DISPLAY 0.574468 (-6425 1200);
PAINT GREEN (-6425 1200);
DISPLAY INVISIBLE (-6425 1200);
FORCEPROP 1 LAST BODY_TYPE PLUMBING
J 0
(-6750 1275);
DISPLAY 0.574468 (-6750 1275);
PAINT GREEN (-6750 1275);
DISPLAY INVISIBLE (-6750 1275);
FORCEPROP 2 LAST CDS_LIB standard
J 0
(-6750 1325);
DISPLAY INVISIBLE (-6750 1325);
FORCEADD TAP..6
(-6750 1425);
FORCEPROP 3 LASTPIN (-6700 1425) SIG_NAME P5E_CPU0_P1_RX_DP<9>
J 0
(-6690 1435);
DISPLAY 0.659574 (-6690 1435);
PAINT MONO (-6690 1435);
DISPLAY INVISIBLE (-6690 1435);
FORCEPROP 1 LASTPIN (-6700 1425) BN 9
J 0
(-6752 1433);
DISPLAY 0.489362 (-6752 1433);
PAINT MONO (-6752 1433);
FORCEPROP 1 LAST PATH I305
J 0
(-6752 1425);
DISPLAY 0.872340 (-6752 1425);
PAINT GREEN (-6752 1425);
DISPLAY INVISIBLE (-6752 1425);
FORCEPROP 1 LAST HDL_TAP TRUE
J 0
(-6425 1300);
DISPLAY 0.574468 (-6425 1300);
PAINT GREEN (-6425 1300);
DISPLAY INVISIBLE (-6425 1300);
FORCEPROP 1 LAST BODY_TYPE PLUMBING
J 0
(-6750 1375);
DISPLAY 0.574468 (-6750 1375);
PAINT GREEN (-6750 1375);
DISPLAY INVISIBLE (-6750 1375);
FORCEPROP 2 LAST CDS_LIB standard
J 0
(-6750 1425);
DISPLAY INVISIBLE (-6750 1425);
FORCEADD OFFPAGE..1
(-8125 2500);
FORCEPROP 2 LAST PATH I306
J 0
(-8075 2575);
DISPLAY 1.021277 (-8075 2575);
DISPLAY INVISIBLE (-8075 2575);
FORCEPROP 1 LAST COMMENT_BODY TRUE
J 0
(-8000 2400);
DISPLAY 0.872340 (-8000 2400);
PAINT GREEN (-8000 2400);
DISPLAY INVISIBLE (-8000 2400);
FORCEPROP 1 LAST OFFPAGE TRUE
J 0
(-7800 2375);
DISPLAY 0.872340 (-7800 2375);
PAINT GREEN (-7800 2375);
DISPLAY INVISIBLE (-7800 2375);
FORCEPROP 2 LAST CDS_LIB standard
J 0
(-8125 2500);
DISPLAY INVISIBLE (-8125 2500);
FORCEADD OFFPAGE..1
(-8125 2550);
FORCEPROP 2 LAST PATH I307
J 0
(-8075 2625);
DISPLAY 1.021277 (-8075 2625);
DISPLAY INVISIBLE (-8075 2625);
FORCEPROP 1 LAST COMMENT_BODY TRUE
J 0
(-8000 2450);
DISPLAY 0.872340 (-8000 2450);
PAINT GREEN (-8000 2450);
DISPLAY INVISIBLE (-8000 2450);
FORCEPROP 1 LAST OFFPAGE TRUE
J 0
(-7800 2425);
DISPLAY 0.872340 (-7800 2425);
PAINT GREEN (-7800 2425);
DISPLAY INVISIBLE (-7800 2425);
FORCEPROP 2 LAST CDS_LIB standard
J 0
(-8125 2550);
DISPLAY INVISIBLE (-8125 2550);
FORCEADD TAP..6
(-6900 1575);
FORCEPROP 3 LASTPIN (-6850 1575) SIG_NAME P5E_CPU0_P1_RX_DN<7>
J 0
(-6840 1585);
DISPLAY 0.659574 (-6840 1585);
PAINT MONO (-6840 1585);
DISPLAY INVISIBLE (-6840 1585);
FORCEPROP 1 LASTPIN (-6850 1575) BN 7
J 0
(-6902 1583);
DISPLAY 0.489362 (-6902 1583);
PAINT MONO (-6902 1583);
FORCEPROP 1 LAST PATH I308
J 0
(-6902 1575);
DISPLAY 0.872340 (-6902 1575);
PAINT GREEN (-6902 1575);
DISPLAY INVISIBLE (-6902 1575);
FORCEPROP 1 LAST HDL_TAP TRUE
J 0
(-6575 1450);
DISPLAY 0.574468 (-6575 1450);
PAINT GREEN (-6575 1450);
DISPLAY INVISIBLE (-6575 1450);
FORCEPROP 1 LAST BODY_TYPE PLUMBING
J 0
(-6900 1525);
DISPLAY 0.574468 (-6900 1525);
PAINT GREEN (-6900 1525);
DISPLAY INVISIBLE (-6900 1525);
FORCEPROP 2 LAST CDS_LIB standard
J 0
(-6900 1575);
DISPLAY INVISIBLE (-6900 1575);
FORCEADD TAP..6
(-6900 1475);
FORCEPROP 3 LASTPIN (-6850 1475) SIG_NAME P5E_CPU0_P1_RX_DN<8>
J 0
(-6840 1485);
DISPLAY 0.659574 (-6840 1485);
PAINT MONO (-6840 1485);
DISPLAY INVISIBLE (-6840 1485);
FORCEPROP 1 LASTPIN (-6850 1475) BN 8
J 0
(-6902 1483);
DISPLAY 0.489362 (-6902 1483);
PAINT MONO (-6902 1483);
FORCEPROP 1 LAST PATH I309
J 0
(-6902 1475);
DISPLAY 0.872340 (-6902 1475);
PAINT GREEN (-6902 1475);
DISPLAY INVISIBLE (-6902 1475);
FORCEPROP 1 LAST HDL_TAP TRUE
J 0
(-6575 1350);
DISPLAY 0.574468 (-6575 1350);
PAINT GREEN (-6575 1350);
DISPLAY INVISIBLE (-6575 1350);
FORCEPROP 1 LAST BODY_TYPE PLUMBING
J 0
(-6900 1425);
DISPLAY 0.574468 (-6900 1425);
PAINT GREEN (-6900 1425);
DISPLAY INVISIBLE (-6900 1425);
FORCEPROP 2 LAST CDS_LIB standard
J 0
(-6900 1475);
DISPLAY INVISIBLE (-6900 1475);
FORCEADD TAP..6
(-6900 1675);
FORCEPROP 3 LASTPIN (-6850 1675) SIG_NAME P5E_CPU0_P1_RX_DN<6>
J 0
(-6840 1685);
DISPLAY 0.659574 (-6840 1685);
PAINT MONO (-6840 1685);
DISPLAY INVISIBLE (-6840 1685);
FORCEPROP 1 LASTPIN (-6850 1675) BN 6
J 0
(-6902 1683);
DISPLAY 0.489362 (-6902 1683);
PAINT MONO (-6902 1683);
FORCEPROP 1 LAST PATH I310
J 0
(-6902 1675);
DISPLAY 0.872340 (-6902 1675);
PAINT GREEN (-6902 1675);
DISPLAY INVISIBLE (-6902 1675);
FORCEPROP 1 LAST HDL_TAP TRUE
J 0
(-6575 1550);
DISPLAY 0.574468 (-6575 1550);
PAINT GREEN (-6575 1550);
DISPLAY INVISIBLE (-6575 1550);
FORCEPROP 1 LAST BODY_TYPE PLUMBING
J 0
(-6900 1625);
DISPLAY 0.574468 (-6900 1625);
PAINT GREEN (-6900 1625);
DISPLAY INVISIBLE (-6900 1625);
FORCEPROP 2 LAST CDS_LIB standard
J 0
(-6900 1675);
DISPLAY INVISIBLE (-6900 1675);
FORCEADD TAP..6
(-6750 1525);
FORCEPROP 3 LASTPIN (-6700 1525) SIG_NAME P5E_CPU0_P1_RX_DP<8>
J 0
(-6690 1535);
DISPLAY 0.659574 (-6690 1535);
PAINT MONO (-6690 1535);
DISPLAY INVISIBLE (-6690 1535);
FORCEPROP 1 LASTPIN (-6700 1525) BN 8
J 0
(-6752 1533);
DISPLAY 0.489362 (-6752 1533);
PAINT MONO (-6752 1533);
FORCEPROP 1 LAST PATH I311
J 0
(-6752 1525);
DISPLAY 0.872340 (-6752 1525);
PAINT GREEN (-6752 1525);
DISPLAY INVISIBLE (-6752 1525);
FORCEPROP 1 LAST HDL_TAP TRUE
J 0
(-6425 1400);
DISPLAY 0.574468 (-6425 1400);
PAINT GREEN (-6425 1400);
DISPLAY INVISIBLE (-6425 1400);
FORCEPROP 1 LAST BODY_TYPE PLUMBING
J 0
(-6750 1475);
DISPLAY 0.574468 (-6750 1475);
PAINT GREEN (-6750 1475);
DISPLAY INVISIBLE (-6750 1475);
FORCEPROP 2 LAST CDS_LIB standard
J 0
(-6750 1525);
DISPLAY INVISIBLE (-6750 1525);
FORCEADD TAP..6
(-6750 1625);
FORCEPROP 3 LASTPIN (-6700 1625) SIG_NAME P5E_CPU0_P1_RX_DP<7>
J 0
(-6690 1635);
DISPLAY 0.659574 (-6690 1635);
PAINT MONO (-6690 1635);
DISPLAY INVISIBLE (-6690 1635);
FORCEPROP 1 LASTPIN (-6700 1625) BN 7
J 0
(-6752 1633);
DISPLAY 0.489362 (-6752 1633);
PAINT MONO (-6752 1633);
FORCEPROP 1 LAST PATH I312
J 0
(-6752 1625);
DISPLAY 0.872340 (-6752 1625);
PAINT GREEN (-6752 1625);
DISPLAY INVISIBLE (-6752 1625);
FORCEPROP 1 LAST HDL_TAP TRUE
J 0
(-6425 1500);
DISPLAY 0.574468 (-6425 1500);
PAINT GREEN (-6425 1500);
DISPLAY INVISIBLE (-6425 1500);
FORCEPROP 1 LAST BODY_TYPE PLUMBING
J 0
(-6750 1575);
DISPLAY 0.574468 (-6750 1575);
PAINT GREEN (-6750 1575);
DISPLAY INVISIBLE (-6750 1575);
FORCEPROP 2 LAST CDS_LIB standard
J 0
(-6750 1625);
DISPLAY INVISIBLE (-6750 1625);
FORCEADD TAP..6
(-6750 1725);
FORCEPROP 3 LASTPIN (-6700 1725) SIG_NAME P5E_CPU0_P1_RX_DP<6>
J 0
(-6690 1735);
DISPLAY 0.659574 (-6690 1735);
PAINT MONO (-6690 1735);
DISPLAY INVISIBLE (-6690 1735);
FORCEPROP 1 LASTPIN (-6700 1725) BN 6
J 0
(-6752 1733);
DISPLAY 0.489362 (-6752 1733);
PAINT MONO (-6752 1733);
FORCEPROP 1 LAST PATH I313
J 0
(-6752 1725);
DISPLAY 0.872340 (-6752 1725);
PAINT GREEN (-6752 1725);
DISPLAY INVISIBLE (-6752 1725);
FORCEPROP 1 LAST HDL_TAP TRUE
J 0
(-6425 1600);
DISPLAY 0.574468 (-6425 1600);
PAINT GREEN (-6425 1600);
DISPLAY INVISIBLE (-6425 1600);
FORCEPROP 1 LAST BODY_TYPE PLUMBING
J 0
(-6750 1675);
DISPLAY 0.574468 (-6750 1675);
PAINT GREEN (-6750 1675);
DISPLAY INVISIBLE (-6750 1675);
FORCEPROP 2 LAST CDS_LIB standard
J 0
(-6750 1725);
DISPLAY INVISIBLE (-6750 1725);
FORCEADD TAP..6
(-6900 1775);
FORCEPROP 3 LASTPIN (-6850 1775) SIG_NAME P5E_CPU0_P1_RX_DN<5>
J 0
(-6840 1785);
DISPLAY 0.659574 (-6840 1785);
PAINT MONO (-6840 1785);
DISPLAY INVISIBLE (-6840 1785);
FORCEPROP 1 LASTPIN (-6850 1775) BN 5
J 0
(-6902 1783);
DISPLAY 0.489362 (-6902 1783);
PAINT MONO (-6902 1783);
FORCEPROP 1 LAST PATH I314
J 0
(-6902 1775);
DISPLAY 0.872340 (-6902 1775);
PAINT GREEN (-6902 1775);
DISPLAY INVISIBLE (-6902 1775);
FORCEPROP 1 LAST HDL_TAP TRUE
J 0
(-6575 1650);
DISPLAY 0.574468 (-6575 1650);
PAINT GREEN (-6575 1650);
DISPLAY INVISIBLE (-6575 1650);
FORCEPROP 1 LAST BODY_TYPE PLUMBING
J 0
(-6900 1725);
DISPLAY 0.574468 (-6900 1725);
PAINT GREEN (-6900 1725);
DISPLAY INVISIBLE (-6900 1725);
FORCEPROP 2 LAST CDS_LIB standard
J 0
(-6900 1775);
DISPLAY INVISIBLE (-6900 1775);
FORCEADD TAP..6
(-6900 1975);
FORCEPROP 3 LASTPIN (-6850 1975) SIG_NAME P5E_CPU0_P1_RX_DN<3>
J 0
(-6840 1985);
DISPLAY 0.659574 (-6840 1985);
PAINT MONO (-6840 1985);
DISPLAY INVISIBLE (-6840 1985);
FORCEPROP 1 LASTPIN (-6850 1975) BN 3
J 0
(-6902 1983);
DISPLAY 0.489362 (-6902 1983);
PAINT MONO (-6902 1983);
FORCEPROP 1 LAST PATH I315
J 0
(-6902 1975);
DISPLAY 0.872340 (-6902 1975);
PAINT GREEN (-6902 1975);
DISPLAY INVISIBLE (-6902 1975);
FORCEPROP 1 LAST HDL_TAP TRUE
J 0
(-6575 1850);
DISPLAY 0.574468 (-6575 1850);
PAINT GREEN (-6575 1850);
DISPLAY INVISIBLE (-6575 1850);
FORCEPROP 1 LAST BODY_TYPE PLUMBING
J 0
(-6900 1925);
DISPLAY 0.574468 (-6900 1925);
PAINT GREEN (-6900 1925);
DISPLAY INVISIBLE (-6900 1925);
FORCEPROP 2 LAST CDS_LIB standard
J 0
(-6900 1975);
DISPLAY INVISIBLE (-6900 1975);
FORCEADD TAP..6
(-6900 1875);
FORCEPROP 3 LASTPIN (-6850 1875) SIG_NAME P5E_CPU0_P1_RX_DN<4>
J 0
(-6840 1885);
DISPLAY 0.659574 (-6840 1885);
PAINT MONO (-6840 1885);
DISPLAY INVISIBLE (-6840 1885);
FORCEPROP 1 LASTPIN (-6850 1875) BN 4
J 0
(-6902 1883);
DISPLAY 0.489362 (-6902 1883);
PAINT MONO (-6902 1883);
FORCEPROP 1 LAST PATH I316
J 0
(-6902 1875);
DISPLAY 0.872340 (-6902 1875);
PAINT GREEN (-6902 1875);
DISPLAY INVISIBLE (-6902 1875);
FORCEPROP 1 LAST HDL_TAP TRUE
J 0
(-6575 1750);
DISPLAY 0.574468 (-6575 1750);
PAINT GREEN (-6575 1750);
DISPLAY INVISIBLE (-6575 1750);
FORCEPROP 1 LAST BODY_TYPE PLUMBING
J 0
(-6900 1825);
DISPLAY 0.574468 (-6900 1825);
PAINT GREEN (-6900 1825);
DISPLAY INVISIBLE (-6900 1825);
FORCEPROP 2 LAST CDS_LIB standard
J 0
(-6900 1875);
DISPLAY INVISIBLE (-6900 1875);
FORCEADD TAP..6
(-6750 1825);
FORCEPROP 3 LASTPIN (-6700 1825) SIG_NAME P5E_CPU0_P1_RX_DP<5>
J 0
(-6690 1835);
DISPLAY 0.659574 (-6690 1835);
PAINT MONO (-6690 1835);
DISPLAY INVISIBLE (-6690 1835);
FORCEPROP 1 LASTPIN (-6700 1825) BN 5
J 0
(-6752 1833);
DISPLAY 0.489362 (-6752 1833);
PAINT MONO (-6752 1833);
FORCEPROP 1 LAST PATH I317
J 0
(-6752 1825);
DISPLAY 0.872340 (-6752 1825);
PAINT GREEN (-6752 1825);
DISPLAY INVISIBLE (-6752 1825);
FORCEPROP 1 LAST HDL_TAP TRUE
J 0
(-6425 1700);
DISPLAY 0.574468 (-6425 1700);
PAINT GREEN (-6425 1700);
DISPLAY INVISIBLE (-6425 1700);
FORCEPROP 1 LAST BODY_TYPE PLUMBING
J 0
(-6750 1775);
DISPLAY 0.574468 (-6750 1775);
PAINT GREEN (-6750 1775);
DISPLAY INVISIBLE (-6750 1775);
FORCEPROP 2 LAST CDS_LIB standard
J 0
(-6750 1825);
DISPLAY INVISIBLE (-6750 1825);
FORCEADD TAP..6
(-6750 1925);
FORCEPROP 3 LASTPIN (-6700 1925) SIG_NAME P5E_CPU0_P1_RX_DP<4>
J 0
(-6690 1935);
DISPLAY 0.659574 (-6690 1935);
PAINT MONO (-6690 1935);
DISPLAY INVISIBLE (-6690 1935);
FORCEPROP 1 LASTPIN (-6700 1925) BN 4
J 0
(-6752 1933);
DISPLAY 0.489362 (-6752 1933);
PAINT MONO (-6752 1933);
FORCEPROP 1 LAST PATH I318
J 0
(-6752 1925);
DISPLAY 0.872340 (-6752 1925);
PAINT GREEN (-6752 1925);
DISPLAY INVISIBLE (-6752 1925);
FORCEPROP 1 LAST HDL_TAP TRUE
J 0
(-6425 1800);
DISPLAY 0.574468 (-6425 1800);
PAINT GREEN (-6425 1800);
DISPLAY INVISIBLE (-6425 1800);
FORCEPROP 1 LAST BODY_TYPE PLUMBING
J 0
(-6750 1875);
DISPLAY 0.574468 (-6750 1875);
PAINT GREEN (-6750 1875);
DISPLAY INVISIBLE (-6750 1875);
FORCEPROP 2 LAST CDS_LIB standard
J 0
(-6750 1925);
DISPLAY INVISIBLE (-6750 1925);
FORCEADD TAP..6
(-6900 2075);
FORCEPROP 3 LASTPIN (-6850 2075) SIG_NAME P5E_CPU0_P1_RX_DN<2>
J 0
(-6840 2085);
DISPLAY 0.659574 (-6840 2085);
PAINT MONO (-6840 2085);
DISPLAY INVISIBLE (-6840 2085);
FORCEPROP 1 LASTPIN (-6850 2075) BN 2
J 0
(-6902 2083);
DISPLAY 0.489362 (-6902 2083);
PAINT MONO (-6902 2083);
FORCEPROP 1 LAST PATH I319
J 0
(-6902 2075);
DISPLAY 0.872340 (-6902 2075);
PAINT GREEN (-6902 2075);
DISPLAY INVISIBLE (-6902 2075);
FORCEPROP 1 LAST HDL_TAP TRUE
J 0
(-6575 1950);
DISPLAY 0.574468 (-6575 1950);
PAINT GREEN (-6575 1950);
DISPLAY INVISIBLE (-6575 1950);
FORCEPROP 1 LAST BODY_TYPE PLUMBING
J 0
(-6900 2025);
DISPLAY 0.574468 (-6900 2025);
PAINT GREEN (-6900 2025);
DISPLAY INVISIBLE (-6900 2025);
FORCEPROP 2 LAST CDS_LIB standard
J 0
(-6900 2075);
DISPLAY INVISIBLE (-6900 2075);
FORCEADD TAP..6
(-6900 2175);
FORCEPROP 3 LASTPIN (-6850 2175) SIG_NAME P5E_CPU0_P1_RX_DN<1>
J 0
(-6840 2185);
DISPLAY 0.659574 (-6840 2185);
PAINT MONO (-6840 2185);
DISPLAY INVISIBLE (-6840 2185);
FORCEPROP 1 LASTPIN (-6850 2175) BN 1
J 0
(-6902 2183);
DISPLAY 0.489362 (-6902 2183);
PAINT MONO (-6902 2183);
FORCEPROP 1 LAST PATH I320
J 0
(-6902 2175);
DISPLAY 0.872340 (-6902 2175);
PAINT GREEN (-6902 2175);
DISPLAY INVISIBLE (-6902 2175);
FORCEPROP 1 LAST HDL_TAP TRUE
J 0
(-6575 2050);
DISPLAY 0.574468 (-6575 2050);
PAINT GREEN (-6575 2050);
DISPLAY INVISIBLE (-6575 2050);
FORCEPROP 1 LAST BODY_TYPE PLUMBING
J 0
(-6900 2125);
DISPLAY 0.574468 (-6900 2125);
PAINT GREEN (-6900 2125);
DISPLAY INVISIBLE (-6900 2125);
FORCEPROP 2 LAST CDS_LIB mstr_standard
J 0
(-6900 2175);
DISPLAY INVISIBLE (-6900 2175);
FORCEADD TAP..6
(-6750 2025);
FORCEPROP 3 LASTPIN (-6700 2025) SIG_NAME P5E_CPU0_P1_RX_DP<3>
J 0
(-6690 2035);
DISPLAY 0.659574 (-6690 2035);
PAINT MONO (-6690 2035);
DISPLAY INVISIBLE (-6690 2035);
FORCEPROP 1 LASTPIN (-6700 2025) BN 3
J 0
(-6752 2033);
DISPLAY 0.489362 (-6752 2033);
PAINT MONO (-6752 2033);
FORCEPROP 1 LAST PATH I321
J 0
(-6752 2025);
DISPLAY 0.872340 (-6752 2025);
PAINT GREEN (-6752 2025);
DISPLAY INVISIBLE (-6752 2025);
FORCEPROP 1 LAST HDL_TAP TRUE
J 0
(-6425 1900);
DISPLAY 0.574468 (-6425 1900);
PAINT GREEN (-6425 1900);
DISPLAY INVISIBLE (-6425 1900);
FORCEPROP 1 LAST BODY_TYPE PLUMBING
J 0
(-6750 1975);
DISPLAY 0.574468 (-6750 1975);
PAINT GREEN (-6750 1975);
DISPLAY INVISIBLE (-6750 1975);
FORCEPROP 2 LAST CDS_LIB standard
J 0
(-6750 2025);
DISPLAY INVISIBLE (-6750 2025);
FORCEADD TAP..6
(-6750 2125);
FORCEPROP 3 LASTPIN (-6700 2125) SIG_NAME P5E_CPU0_P1_RX_DP<2>
J 0
(-6690 2135);
DISPLAY 0.659574 (-6690 2135);
PAINT MONO (-6690 2135);
DISPLAY INVISIBLE (-6690 2135);
FORCEPROP 1 LASTPIN (-6700 2125) BN 2
J 0
(-6752 2133);
DISPLAY 0.489362 (-6752 2133);
PAINT MONO (-6752 2133);
FORCEPROP 1 LAST PATH I322
J 0
(-6752 2125);
DISPLAY 0.872340 (-6752 2125);
PAINT GREEN (-6752 2125);
DISPLAY INVISIBLE (-6752 2125);
FORCEPROP 1 LAST HDL_TAP TRUE
J 0
(-6425 2000);
DISPLAY 0.574468 (-6425 2000);
PAINT GREEN (-6425 2000);
DISPLAY INVISIBLE (-6425 2000);
FORCEPROP 1 LAST BODY_TYPE PLUMBING
J 0
(-6750 2075);
DISPLAY 0.574468 (-6750 2075);
PAINT GREEN (-6750 2075);
DISPLAY INVISIBLE (-6750 2075);
FORCEPROP 2 LAST CDS_LIB mstr_standard
J 0
(-6750 2125);
DISPLAY INVISIBLE (-6750 2125);
FORCEADD TAP..6
(-6750 2225);
FORCEPROP 3 LASTPIN (-6700 2225) SIG_NAME P5E_CPU0_P1_RX_DP<1>
J 0
(-6690 2235);
DISPLAY 0.659574 (-6690 2235);
PAINT MONO (-6690 2235);
DISPLAY INVISIBLE (-6690 2235);
FORCEPROP 1 LASTPIN (-6700 2225) BN 1
J 0
(-6752 2233);
DISPLAY 0.489362 (-6752 2233);
PAINT MONO (-6752 2233);
FORCEPROP 1 LAST PATH I323
J 0
(-6752 2225);
DISPLAY 0.872340 (-6752 2225);
PAINT GREEN (-6752 2225);
DISPLAY INVISIBLE (-6752 2225);
FORCEPROP 1 LAST HDL_TAP TRUE
J 0
(-6425 2100);
DISPLAY 0.574468 (-6425 2100);
PAINT GREEN (-6425 2100);
DISPLAY INVISIBLE (-6425 2100);
FORCEPROP 1 LAST BODY_TYPE PLUMBING
J 0
(-6750 2175);
DISPLAY 0.574468 (-6750 2175);
PAINT GREEN (-6750 2175);
DISPLAY INVISIBLE (-6750 2175);
FORCEPROP 2 LAST CDS_LIB mstr_standard
J 0
(-6750 2225);
DISPLAY INVISIBLE (-6750 2225);
FORCEADD TAP..6
(-6900 2275);
FORCEPROP 3 LASTPIN (-6850 2275) SIG_NAME P5E_CPU0_P1_RX_DN<0>
J 0
(-6840 2285);
DISPLAY 0.659574 (-6840 2285);
PAINT MONO (-6840 2285);
DISPLAY INVISIBLE (-6840 2285);
FORCEPROP 1 LASTPIN (-6850 2275) BN 0
J 0
(-6902 2283);
DISPLAY 0.489362 (-6902 2283);
PAINT MONO (-6902 2283);
FORCEPROP 1 LAST PATH I324
J 0
(-6902 2275);
DISPLAY 0.872340 (-6902 2275);
PAINT GREEN (-6902 2275);
DISPLAY INVISIBLE (-6902 2275);
FORCEPROP 1 LAST HDL_TAP TRUE
J 0
(-6575 2150);
DISPLAY 0.574468 (-6575 2150);
PAINT GREEN (-6575 2150);
DISPLAY INVISIBLE (-6575 2150);
FORCEPROP 1 LAST BODY_TYPE PLUMBING
J 0
(-6900 2225);
DISPLAY 0.574468 (-6900 2225);
PAINT GREEN (-6900 2225);
DISPLAY INVISIBLE (-6900 2225);
FORCEPROP 2 LAST CDS_LIB mstr_standard
J 0
(-6900 2275);
DISPLAY INVISIBLE (-6900 2275);
FORCEADD TAP..6
(-6750 2325);
FORCEPROP 3 LASTPIN (-6700 2325) SIG_NAME P5E_CPU0_P1_RX_DP<0>
J 0
(-6690 2335);
DISPLAY 0.659574 (-6690 2335);
PAINT MONO (-6690 2335);
DISPLAY INVISIBLE (-6690 2335);
FORCEPROP 1 LASTPIN (-6700 2325) BN 0
J 0
(-6752 2333);
DISPLAY 0.489362 (-6752 2333);
PAINT MONO (-6752 2333);
FORCEPROP 1 LAST PATH I325
J 0
(-6752 2325);
DISPLAY 0.872340 (-6752 2325);
PAINT GREEN (-6752 2325);
DISPLAY INVISIBLE (-6752 2325);
FORCEPROP 1 LAST HDL_TAP TRUE
J 0
(-6425 2200);
DISPLAY 0.574468 (-6425 2200);
PAINT GREEN (-6425 2200);
DISPLAY INVISIBLE (-6425 2200);
FORCEPROP 1 LAST BODY_TYPE PLUMBING
J 0
(-6750 2275);
DISPLAY 0.574468 (-6750 2275);
PAINT GREEN (-6750 2275);
DISPLAY INVISIBLE (-6750 2275);
FORCEPROP 2 LAST CDS_LIB mstr_standard
J 0
(-6750 2325);
DISPLAY INVISIBLE (-6750 2325);
FORCEADD TAP..6
(-6825 4450);
FORCEPROP 3 LASTPIN (-6775 4450) SIG_NAME P5E_CPU0_P0_RX_DN<13>
J 0
(-6765 4460);
DISPLAY 0.659574 (-6765 4460);
PAINT MONO (-6765 4460);
DISPLAY INVISIBLE (-6765 4460);
FORCEPROP 1 LASTPIN (-6775 4450) BN 13
J 0
(-6827 4458);
DISPLAY 0.680851 (-6827 4458);
PAINT MONO (-6827 4458);
FORCEPROP 1 LAST HDL_TAP TRUE
J 0
(-6500 4325);
DISPLAY 0.574468 (-6500 4325);
PAINT GREEN (-6500 4325);
DISPLAY INVISIBLE (-6500 4325);
FORCEPROP 1 LAST BODY_TYPE PLUMBING
J 0
(-6825 4400);
DISPLAY 0.574468 (-6825 4400);
PAINT GREEN (-6825 4400);
DISPLAY INVISIBLE (-6825 4400);
FORCEPROP 1 LAST PATH I326
J 0
(-6827 4450);
DISPLAY 0.872340 (-6827 4450);
PAINT GREEN (-6827 4450);
DISPLAY INVISIBLE (-6827 4450);
FORCEPROP 2 LAST CDS_LIB standard
J 0
(-6825 4450);
DISPLAY INVISIBLE (-6825 4450);
FORCEADD TAP..6
(-6675 4300);
FORCEPROP 3 LASTPIN (-6625 4300) SIG_NAME P5E_CPU0_P0_RX_DP<15>
J 0
(-6615 4310);
DISPLAY 0.659574 (-6615 4310);
PAINT MONO (-6615 4310);
DISPLAY INVISIBLE (-6615 4310);
FORCEPROP 1 LASTPIN (-6625 4300) BN 15
J 0
(-6677 4308);
DISPLAY 0.680851 (-6677 4308);
PAINT MONO (-6677 4308);
FORCEPROP 1 LAST HDL_TAP TRUE
J 0
(-6350 4175);
DISPLAY 0.574468 (-6350 4175);
PAINT GREEN (-6350 4175);
DISPLAY INVISIBLE (-6350 4175);
FORCEPROP 1 LAST BODY_TYPE PLUMBING
J 0
(-6675 4250);
DISPLAY 0.574468 (-6675 4250);
PAINT GREEN (-6675 4250);
DISPLAY INVISIBLE (-6675 4250);
FORCEPROP 1 LAST PATH I327
J 0
(-6677 4300);
DISPLAY 0.872340 (-6677 4300);
PAINT GREEN (-6677 4300);
DISPLAY INVISIBLE (-6677 4300);
FORCEPROP 2 LAST CDS_LIB standard
J 0
(-6675 4300);
DISPLAY INVISIBLE (-6675 4300);
FORCEADD TAP..6
(-6675 5800);
FORCEPROP 3 LASTPIN (-6625 5800) SIG_NAME P5E_CPU0_P0_RX_DP<0>
J 0
(-6615 5810);
DISPLAY 0.659574 (-6615 5810);
PAINT MONO (-6615 5810);
DISPLAY INVISIBLE (-6615 5810);
FORCEPROP 1 LASTPIN (-6625 5800) BN 0
J 0
(-6677 5808);
DISPLAY 0.680851 (-6677 5808);
PAINT MONO (-6677 5808);
FORCEPROP 1 LAST HDL_TAP TRUE
J 0
(-6350 5675);
DISPLAY 0.574468 (-6350 5675);
PAINT GREEN (-6350 5675);
DISPLAY INVISIBLE (-6350 5675);
FORCEPROP 1 LAST BODY_TYPE PLUMBING
J 0
(-6675 5750);
DISPLAY 0.574468 (-6675 5750);
PAINT GREEN (-6675 5750);
DISPLAY INVISIBLE (-6675 5750);
FORCEPROP 1 LAST PATH I328
J 0
(-6677 5800);
DISPLAY 0.872340 (-6677 5800);
PAINT GREEN (-6677 5800);
DISPLAY INVISIBLE (-6677 5800);
FORCEPROP 2 LAST CDS_LIB mstr_standard
J 0
(-6675 5800);
DISPLAY INVISIBLE (-6675 5800);
FORCEADD TAP..6
(-6675 5700);
FORCEPROP 3 LASTPIN (-6625 5700) SIG_NAME P5E_CPU0_P0_RX_DP<1>
J 0
(-6615 5710);
DISPLAY 0.659574 (-6615 5710);
PAINT MONO (-6615 5710);
DISPLAY INVISIBLE (-6615 5710);
FORCEPROP 1 LASTPIN (-6625 5700) BN 1
J 0
(-6677 5708);
DISPLAY 0.680851 (-6677 5708);
PAINT MONO (-6677 5708);
FORCEPROP 1 LAST HDL_TAP TRUE
J 0
(-6350 5575);
DISPLAY 0.574468 (-6350 5575);
PAINT GREEN (-6350 5575);
DISPLAY INVISIBLE (-6350 5575);
FORCEPROP 1 LAST BODY_TYPE PLUMBING
J 0
(-6675 5650);
DISPLAY 0.574468 (-6675 5650);
PAINT GREEN (-6675 5650);
DISPLAY INVISIBLE (-6675 5650);
FORCEPROP 1 LAST PATH I329
J 0
(-6677 5700);
DISPLAY 0.872340 (-6677 5700);
PAINT GREEN (-6677 5700);
DISPLAY INVISIBLE (-6677 5700);
FORCEPROP 2 LAST CDS_LIB mstr_standard
J 0
(-6675 5700);
DISPLAY INVISIBLE (-6675 5700);
FORCEADD TAP..6
(-6675 5600);
FORCEPROP 3 LASTPIN (-6625 5600) SIG_NAME P5E_CPU0_P0_RX_DP<2>
J 0
(-6615 5610);
DISPLAY 0.659574 (-6615 5610);
PAINT MONO (-6615 5610);
DISPLAY INVISIBLE (-6615 5610);
FORCEPROP 1 LASTPIN (-6625 5600) BN 2
J 0
(-6677 5608);
DISPLAY 0.680851 (-6677 5608);
PAINT MONO (-6677 5608);
FORCEPROP 1 LAST HDL_TAP TRUE
J 0
(-6350 5475);
DISPLAY 0.574468 (-6350 5475);
PAINT GREEN (-6350 5475);
DISPLAY INVISIBLE (-6350 5475);
FORCEPROP 1 LAST BODY_TYPE PLUMBING
J 0
(-6675 5550);
DISPLAY 0.574468 (-6675 5550);
PAINT GREEN (-6675 5550);
DISPLAY INVISIBLE (-6675 5550);
FORCEPROP 1 LAST PATH I330
J 0
(-6677 5600);
DISPLAY 0.872340 (-6677 5600);
PAINT GREEN (-6677 5600);
DISPLAY INVISIBLE (-6677 5600);
FORCEPROP 2 LAST CDS_LIB mstr_standard
J 0
(-6675 5600);
DISPLAY INVISIBLE (-6675 5600);
FORCEADD TAP..6
(-6825 5550);
FORCEPROP 3 LASTPIN (-6775 5550) SIG_NAME P5E_CPU0_P0_RX_DN<2>
J 0
(-6765 5560);
DISPLAY 0.659574 (-6765 5560);
PAINT MONO (-6765 5560);
DISPLAY INVISIBLE (-6765 5560);
FORCEPROP 1 LASTPIN (-6775 5550) BN 2
J 0
(-6827 5558);
DISPLAY 0.680851 (-6827 5558);
PAINT MONO (-6827 5558);
FORCEPROP 1 LAST HDL_TAP TRUE
J 0
(-6500 5425);
DISPLAY 0.574468 (-6500 5425);
PAINT GREEN (-6500 5425);
DISPLAY INVISIBLE (-6500 5425);
FORCEPROP 1 LAST BODY_TYPE PLUMBING
J 0
(-6825 5500);
DISPLAY 0.574468 (-6825 5500);
PAINT GREEN (-6825 5500);
DISPLAY INVISIBLE (-6825 5500);
FORCEPROP 1 LAST PATH I331
J 0
(-6827 5550);
DISPLAY 0.872340 (-6827 5550);
PAINT GREEN (-6827 5550);
DISPLAY INVISIBLE (-6827 5550);
FORCEPROP 2 LAST CDS_LIB standard
J 0
(-6825 5550);
DISPLAY INVISIBLE (-6825 5550);
FORCEADD TAP..6
(-6825 5650);
FORCEPROP 3 LASTPIN (-6775 5650) SIG_NAME P5E_CPU0_P0_RX_DN<1>
J 0
(-6765 5660);
DISPLAY 0.659574 (-6765 5660);
PAINT MONO (-6765 5660);
DISPLAY INVISIBLE (-6765 5660);
FORCEPROP 1 LASTPIN (-6775 5650) BN 1
J 0
(-6827 5658);
DISPLAY 0.680851 (-6827 5658);
PAINT MONO (-6827 5658);
FORCEPROP 1 LAST HDL_TAP TRUE
J 0
(-6500 5525);
DISPLAY 0.574468 (-6500 5525);
PAINT GREEN (-6500 5525);
DISPLAY INVISIBLE (-6500 5525);
FORCEPROP 1 LAST BODY_TYPE PLUMBING
J 0
(-6825 5600);
DISPLAY 0.574468 (-6825 5600);
PAINT GREEN (-6825 5600);
DISPLAY INVISIBLE (-6825 5600);
FORCEPROP 1 LAST PATH I332
J 0
(-6827 5650);
DISPLAY 0.872340 (-6827 5650);
PAINT GREEN (-6827 5650);
DISPLAY INVISIBLE (-6827 5650);
FORCEPROP 2 LAST CDS_LIB mstr_standard
J 0
(-6825 5650);
DISPLAY INVISIBLE (-6825 5650);
FORCEADD TAP..6
(-6825 5750);
FORCEPROP 3 LASTPIN (-6775 5750) SIG_NAME P5E_CPU0_P0_RX_DN<0>
J 0
(-6765 5760);
DISPLAY 0.659574 (-6765 5760);
PAINT MONO (-6765 5760);
DISPLAY INVISIBLE (-6765 5760);
FORCEPROP 1 LASTPIN (-6775 5750) BN 0
J 0
(-6827 5758);
DISPLAY 0.680851 (-6827 5758);
PAINT MONO (-6827 5758);
FORCEPROP 1 LAST HDL_TAP TRUE
J 0
(-6500 5625);
DISPLAY 0.574468 (-6500 5625);
PAINT GREEN (-6500 5625);
DISPLAY INVISIBLE (-6500 5625);
FORCEPROP 1 LAST BODY_TYPE PLUMBING
J 0
(-6825 5700);
DISPLAY 0.574468 (-6825 5700);
PAINT GREEN (-6825 5700);
DISPLAY INVISIBLE (-6825 5700);
FORCEPROP 1 LAST PATH I333
J 0
(-6827 5750);
DISPLAY 0.872340 (-6827 5750);
PAINT GREEN (-6827 5750);
DISPLAY INVISIBLE (-6827 5750);
FORCEPROP 2 LAST CDS_LIB mstr_standard
J 0
(-6825 5750);
DISPLAY INVISIBLE (-6825 5750);
FORCEADD TAP..6
(-6675 5500);
FORCEPROP 3 LASTPIN (-6625 5500) SIG_NAME P5E_CPU0_P0_RX_DP<3>
J 0
(-6615 5510);
DISPLAY 0.659574 (-6615 5510);
PAINT MONO (-6615 5510);
DISPLAY INVISIBLE (-6615 5510);
FORCEPROP 1 LASTPIN (-6625 5500) BN 3
J 0
(-6677 5508);
DISPLAY 0.680851 (-6677 5508);
PAINT MONO (-6677 5508);
FORCEPROP 1 LAST HDL_TAP TRUE
J 0
(-6350 5375);
DISPLAY 0.574468 (-6350 5375);
PAINT GREEN (-6350 5375);
DISPLAY INVISIBLE (-6350 5375);
FORCEPROP 1 LAST BODY_TYPE PLUMBING
J 0
(-6675 5450);
DISPLAY 0.574468 (-6675 5450);
PAINT GREEN (-6675 5450);
DISPLAY INVISIBLE (-6675 5450);
FORCEPROP 1 LAST PATH I334
J 0
(-6677 5500);
DISPLAY 0.872340 (-6677 5500);
PAINT GREEN (-6677 5500);
DISPLAY INVISIBLE (-6677 5500);
FORCEPROP 2 LAST CDS_LIB standard
J 0
(-6675 5500);
DISPLAY INVISIBLE (-6675 5500);
FORCEADD TAP..6
(-6675 5400);
FORCEPROP 3 LASTPIN (-6625 5400) SIG_NAME P5E_CPU0_P0_RX_DP<4>
J 0
(-6615 5410);
DISPLAY 0.659574 (-6615 5410);
PAINT MONO (-6615 5410);
DISPLAY INVISIBLE (-6615 5410);
FORCEPROP 1 LASTPIN (-6625 5400) BN 4
J 0
(-6677 5408);
DISPLAY 0.680851 (-6677 5408);
PAINT MONO (-6677 5408);
FORCEPROP 1 LAST HDL_TAP TRUE
J 0
(-6350 5275);
DISPLAY 0.574468 (-6350 5275);
PAINT GREEN (-6350 5275);
DISPLAY INVISIBLE (-6350 5275);
FORCEPROP 1 LAST BODY_TYPE PLUMBING
J 0
(-6675 5350);
DISPLAY 0.574468 (-6675 5350);
PAINT GREEN (-6675 5350);
DISPLAY INVISIBLE (-6675 5350);
FORCEPROP 1 LAST PATH I335
J 0
(-6677 5400);
DISPLAY 0.872340 (-6677 5400);
PAINT GREEN (-6677 5400);
DISPLAY INVISIBLE (-6677 5400);
FORCEPROP 2 LAST CDS_LIB standard
J 0
(-6675 5400);
DISPLAY INVISIBLE (-6675 5400);
FORCEADD TAP..6
(-6675 5300);
FORCEPROP 3 LASTPIN (-6625 5300) SIG_NAME P5E_CPU0_P0_RX_DP<5>
J 0
(-6615 5310);
DISPLAY 0.659574 (-6615 5310);
PAINT MONO (-6615 5310);
DISPLAY INVISIBLE (-6615 5310);
FORCEPROP 1 LASTPIN (-6625 5300) BN 5
J 0
(-6677 5308);
DISPLAY 0.680851 (-6677 5308);
PAINT MONO (-6677 5308);
FORCEPROP 1 LAST HDL_TAP TRUE
J 0
(-6350 5175);
DISPLAY 0.574468 (-6350 5175);
PAINT GREEN (-6350 5175);
DISPLAY INVISIBLE (-6350 5175);
FORCEPROP 1 LAST BODY_TYPE PLUMBING
J 0
(-6675 5250);
DISPLAY 0.574468 (-6675 5250);
PAINT GREEN (-6675 5250);
DISPLAY INVISIBLE (-6675 5250);
FORCEPROP 1 LAST PATH I336
J 0
(-6677 5300);
DISPLAY 0.872340 (-6677 5300);
PAINT GREEN (-6677 5300);
DISPLAY INVISIBLE (-6677 5300);
FORCEPROP 2 LAST CDS_LIB standard
J 0
(-6675 5300);
DISPLAY INVISIBLE (-6675 5300);
FORCEADD TAP..6
(-6675 5200);
FORCEPROP 3 LASTPIN (-6625 5200) SIG_NAME P5E_CPU0_P0_RX_DP<6>
J 0
(-6615 5210);
DISPLAY 0.659574 (-6615 5210);
PAINT MONO (-6615 5210);
DISPLAY INVISIBLE (-6615 5210);
FORCEPROP 1 LASTPIN (-6625 5200) BN 6
J 0
(-6677 5208);
DISPLAY 0.680851 (-6677 5208);
PAINT MONO (-6677 5208);
FORCEPROP 1 LAST HDL_TAP TRUE
J 0
(-6350 5075);
DISPLAY 0.574468 (-6350 5075);
PAINT GREEN (-6350 5075);
DISPLAY INVISIBLE (-6350 5075);
FORCEPROP 1 LAST BODY_TYPE PLUMBING
J 0
(-6675 5150);
DISPLAY 0.574468 (-6675 5150);
PAINT GREEN (-6675 5150);
DISPLAY INVISIBLE (-6675 5150);
FORCEPROP 1 LAST PATH I337
J 0
(-6677 5200);
DISPLAY 0.872340 (-6677 5200);
PAINT GREEN (-6677 5200);
DISPLAY INVISIBLE (-6677 5200);
FORCEPROP 2 LAST CDS_LIB standard
J 0
(-6675 5200);
DISPLAY INVISIBLE (-6675 5200);
FORCEADD TAP..6
(-6675 5100);
FORCEPROP 3 LASTPIN (-6625 5100) SIG_NAME P5E_CPU0_P0_RX_DP<7>
J 0
(-6615 5110);
DISPLAY 0.659574 (-6615 5110);
PAINT MONO (-6615 5110);
DISPLAY INVISIBLE (-6615 5110);
FORCEPROP 1 LASTPIN (-6625 5100) BN 7
J 0
(-6677 5108);
DISPLAY 0.680851 (-6677 5108);
PAINT MONO (-6677 5108);
FORCEPROP 1 LAST HDL_TAP TRUE
J 0
(-6350 4975);
DISPLAY 0.574468 (-6350 4975);
PAINT GREEN (-6350 4975);
DISPLAY INVISIBLE (-6350 4975);
FORCEPROP 1 LAST BODY_TYPE PLUMBING
J 0
(-6675 5050);
DISPLAY 0.574468 (-6675 5050);
PAINT GREEN (-6675 5050);
DISPLAY INVISIBLE (-6675 5050);
FORCEPROP 1 LAST PATH I338
J 0
(-6677 5100);
DISPLAY 0.872340 (-6677 5100);
PAINT GREEN (-6677 5100);
DISPLAY INVISIBLE (-6677 5100);
FORCEPROP 2 LAST CDS_LIB standard
J 0
(-6675 5100);
DISPLAY INVISIBLE (-6675 5100);
FORCEADD TAP..6
(-6825 5350);
FORCEPROP 3 LASTPIN (-6775 5350) SIG_NAME P5E_CPU0_P0_RX_DN<4>
J 0
(-6765 5360);
DISPLAY 0.659574 (-6765 5360);
PAINT MONO (-6765 5360);
DISPLAY INVISIBLE (-6765 5360);
FORCEPROP 1 LASTPIN (-6775 5350) BN 4
J 0
(-6827 5358);
DISPLAY 0.680851 (-6827 5358);
PAINT MONO (-6827 5358);
FORCEPROP 1 LAST HDL_TAP TRUE
J 0
(-6500 5225);
DISPLAY 0.574468 (-6500 5225);
PAINT GREEN (-6500 5225);
DISPLAY INVISIBLE (-6500 5225);
FORCEPROP 1 LAST BODY_TYPE PLUMBING
J 0
(-6825 5300);
DISPLAY 0.574468 (-6825 5300);
PAINT GREEN (-6825 5300);
DISPLAY INVISIBLE (-6825 5300);
FORCEPROP 1 LAST PATH I339
J 0
(-6827 5350);
DISPLAY 0.872340 (-6827 5350);
PAINT GREEN (-6827 5350);
DISPLAY INVISIBLE (-6827 5350);
FORCEPROP 2 LAST CDS_LIB standard
J 0
(-6825 5350);
DISPLAY INVISIBLE (-6825 5350);
FORCEADD TAP..6
(-6825 5450);
FORCEPROP 3 LASTPIN (-6775 5450) SIG_NAME P5E_CPU0_P0_RX_DN<3>
J 0
(-6765 5460);
DISPLAY 0.659574 (-6765 5460);
PAINT MONO (-6765 5460);
DISPLAY INVISIBLE (-6765 5460);
FORCEPROP 1 LASTPIN (-6775 5450) BN 3
J 0
(-6827 5458);
DISPLAY 0.680851 (-6827 5458);
PAINT MONO (-6827 5458);
FORCEPROP 1 LAST HDL_TAP TRUE
J 0
(-6500 5325);
DISPLAY 0.574468 (-6500 5325);
PAINT GREEN (-6500 5325);
DISPLAY INVISIBLE (-6500 5325);
FORCEPROP 1 LAST BODY_TYPE PLUMBING
J 0
(-6825 5400);
DISPLAY 0.574468 (-6825 5400);
PAINT GREEN (-6825 5400);
DISPLAY INVISIBLE (-6825 5400);
FORCEPROP 1 LAST PATH I340
J 0
(-6827 5450);
DISPLAY 0.872340 (-6827 5450);
PAINT GREEN (-6827 5450);
DISPLAY INVISIBLE (-6827 5450);
FORCEPROP 2 LAST CDS_LIB standard
J 0
(-6825 5450);
DISPLAY INVISIBLE (-6825 5450);
FORCEADD TAP..6
(-6825 5250);
FORCEPROP 3 LASTPIN (-6775 5250) SIG_NAME P5E_CPU0_P0_RX_DN<5>
J 0
(-6765 5260);
DISPLAY 0.659574 (-6765 5260);
PAINT MONO (-6765 5260);
DISPLAY INVISIBLE (-6765 5260);
FORCEPROP 1 LASTPIN (-6775 5250) BN 5
J 0
(-6827 5258);
DISPLAY 0.680851 (-6827 5258);
PAINT MONO (-6827 5258);
FORCEPROP 1 LAST HDL_TAP TRUE
J 0
(-6500 5125);
DISPLAY 0.574468 (-6500 5125);
PAINT GREEN (-6500 5125);
DISPLAY INVISIBLE (-6500 5125);
FORCEPROP 1 LAST BODY_TYPE PLUMBING
J 0
(-6825 5200);
DISPLAY 0.574468 (-6825 5200);
PAINT GREEN (-6825 5200);
DISPLAY INVISIBLE (-6825 5200);
FORCEPROP 1 LAST PATH I341
J 0
(-6827 5250);
DISPLAY 0.872340 (-6827 5250);
PAINT GREEN (-6827 5250);
DISPLAY INVISIBLE (-6827 5250);
FORCEPROP 2 LAST CDS_LIB standard
J 0
(-6825 5250);
DISPLAY INVISIBLE (-6825 5250);
FORCEADD TAP..6
(-6825 5150);
FORCEPROP 3 LASTPIN (-6775 5150) SIG_NAME P5E_CPU0_P0_RX_DN<6>
J 0
(-6765 5160);
DISPLAY 0.659574 (-6765 5160);
PAINT MONO (-6765 5160);
DISPLAY INVISIBLE (-6765 5160);
FORCEPROP 1 LASTPIN (-6775 5150) BN 6
J 0
(-6827 5158);
DISPLAY 0.680851 (-6827 5158);
PAINT MONO (-6827 5158);
FORCEPROP 1 LAST HDL_TAP TRUE
J 0
(-6500 5025);
DISPLAY 0.574468 (-6500 5025);
PAINT GREEN (-6500 5025);
DISPLAY INVISIBLE (-6500 5025);
FORCEPROP 1 LAST BODY_TYPE PLUMBING
J 0
(-6825 5100);
DISPLAY 0.574468 (-6825 5100);
PAINT GREEN (-6825 5100);
DISPLAY INVISIBLE (-6825 5100);
FORCEPROP 1 LAST PATH I342
J 0
(-6827 5150);
DISPLAY 0.872340 (-6827 5150);
PAINT GREEN (-6827 5150);
DISPLAY INVISIBLE (-6827 5150);
FORCEPROP 2 LAST CDS_LIB standard
J 0
(-6825 5150);
DISPLAY INVISIBLE (-6825 5150);
FORCEADD TAP..6
(-6825 5050);
FORCEPROP 3 LASTPIN (-6775 5050) SIG_NAME P5E_CPU0_P0_RX_DN<7>
J 0
(-6765 5060);
DISPLAY 0.659574 (-6765 5060);
PAINT MONO (-6765 5060);
DISPLAY INVISIBLE (-6765 5060);
FORCEPROP 1 LASTPIN (-6775 5050) BN 7
J 0
(-6827 5058);
DISPLAY 0.680851 (-6827 5058);
PAINT MONO (-6827 5058);
FORCEPROP 1 LAST HDL_TAP TRUE
J 0
(-6500 4925);
DISPLAY 0.574468 (-6500 4925);
PAINT GREEN (-6500 4925);
DISPLAY INVISIBLE (-6500 4925);
FORCEPROP 1 LAST BODY_TYPE PLUMBING
J 0
(-6825 5000);
DISPLAY 0.574468 (-6825 5000);
PAINT GREEN (-6825 5000);
DISPLAY INVISIBLE (-6825 5000);
FORCEPROP 1 LAST PATH I343
J 0
(-6827 5050);
DISPLAY 0.872340 (-6827 5050);
PAINT GREEN (-6827 5050);
DISPLAY INVISIBLE (-6827 5050);
FORCEPROP 2 LAST CDS_LIB standard
J 0
(-6825 5050);
DISPLAY INVISIBLE (-6825 5050);
FORCEADD TAP..6
(-6675 5000);
FORCEPROP 3 LASTPIN (-6625 5000) SIG_NAME P5E_CPU0_P0_RX_DP<8>
J 0
(-6615 5010);
DISPLAY 0.659574 (-6615 5010);
PAINT MONO (-6615 5010);
DISPLAY INVISIBLE (-6615 5010);
FORCEPROP 1 LASTPIN (-6625 5000) BN 8
J 0
(-6677 5008);
DISPLAY 0.680851 (-6677 5008);
PAINT MONO (-6677 5008);
FORCEPROP 1 LAST HDL_TAP TRUE
J 0
(-6350 4875);
DISPLAY 0.574468 (-6350 4875);
PAINT GREEN (-6350 4875);
DISPLAY INVISIBLE (-6350 4875);
FORCEPROP 1 LAST BODY_TYPE PLUMBING
J 0
(-6675 4950);
DISPLAY 0.574468 (-6675 4950);
PAINT GREEN (-6675 4950);
DISPLAY INVISIBLE (-6675 4950);
FORCEPROP 1 LAST PATH I344
J 0
(-6677 5000);
DISPLAY 0.872340 (-6677 5000);
PAINT GREEN (-6677 5000);
DISPLAY INVISIBLE (-6677 5000);
FORCEPROP 2 LAST CDS_LIB standard
J 0
(-6675 5000);
DISPLAY INVISIBLE (-6675 5000);
FORCEADD TAP..6
(-6675 4900);
FORCEPROP 3 LASTPIN (-6625 4900) SIG_NAME P5E_CPU0_P0_RX_DP<9>
J 0
(-6615 4910);
DISPLAY 0.659574 (-6615 4910);
PAINT MONO (-6615 4910);
DISPLAY INVISIBLE (-6615 4910);
FORCEPROP 1 LASTPIN (-6625 4900) BN 9
J 0
(-6677 4908);
DISPLAY 0.680851 (-6677 4908);
PAINT MONO (-6677 4908);
FORCEPROP 1 LAST HDL_TAP TRUE
J 0
(-6350 4775);
DISPLAY 0.574468 (-6350 4775);
PAINT GREEN (-6350 4775);
DISPLAY INVISIBLE (-6350 4775);
FORCEPROP 1 LAST BODY_TYPE PLUMBING
J 0
(-6675 4850);
DISPLAY 0.574468 (-6675 4850);
PAINT GREEN (-6675 4850);
DISPLAY INVISIBLE (-6675 4850);
FORCEPROP 1 LAST PATH I345
J 0
(-6677 4900);
DISPLAY 0.872340 (-6677 4900);
PAINT GREEN (-6677 4900);
DISPLAY INVISIBLE (-6677 4900);
FORCEPROP 2 LAST CDS_LIB standard
J 0
(-6675 4900);
DISPLAY INVISIBLE (-6675 4900);
FORCEADD TAP..6
(-6675 4800);
FORCEPROP 3 LASTPIN (-6625 4800) SIG_NAME P5E_CPU0_P0_RX_DP<10>
J 0
(-6615 4810);
DISPLAY 0.659574 (-6615 4810);
PAINT MONO (-6615 4810);
DISPLAY INVISIBLE (-6615 4810);
FORCEPROP 1 LASTPIN (-6625 4800) BN 10
J 0
(-6677 4808);
DISPLAY 0.680851 (-6677 4808);
PAINT MONO (-6677 4808);
FORCEPROP 1 LAST HDL_TAP TRUE
J 0
(-6350 4675);
DISPLAY 0.574468 (-6350 4675);
PAINT GREEN (-6350 4675);
DISPLAY INVISIBLE (-6350 4675);
FORCEPROP 1 LAST BODY_TYPE PLUMBING
J 0
(-6675 4750);
DISPLAY 0.574468 (-6675 4750);
PAINT GREEN (-6675 4750);
DISPLAY INVISIBLE (-6675 4750);
FORCEPROP 1 LAST PATH I346
J 0
(-6677 4800);
DISPLAY 0.872340 (-6677 4800);
PAINT GREEN (-6677 4800);
DISPLAY INVISIBLE (-6677 4800);
FORCEPROP 2 LAST CDS_LIB standard
J 0
(-6675 4800);
DISPLAY INVISIBLE (-6675 4800);
FORCEADD TAP..6
(-6675 4700);
FORCEPROP 3 LASTPIN (-6625 4700) SIG_NAME P5E_CPU0_P0_RX_DP<11>
J 0
(-6615 4710);
DISPLAY 0.659574 (-6615 4710);
PAINT MONO (-6615 4710);
DISPLAY INVISIBLE (-6615 4710);
FORCEPROP 1 LASTPIN (-6625 4700) BN 11
J 0
(-6677 4708);
DISPLAY 0.680851 (-6677 4708);
PAINT MONO (-6677 4708);
FORCEPROP 1 LAST HDL_TAP TRUE
J 0
(-6350 4575);
DISPLAY 0.574468 (-6350 4575);
PAINT GREEN (-6350 4575);
DISPLAY INVISIBLE (-6350 4575);
FORCEPROP 1 LAST BODY_TYPE PLUMBING
J 0
(-6675 4650);
DISPLAY 0.574468 (-6675 4650);
PAINT GREEN (-6675 4650);
DISPLAY INVISIBLE (-6675 4650);
FORCEPROP 1 LAST PATH I347
J 0
(-6677 4700);
DISPLAY 0.872340 (-6677 4700);
PAINT GREEN (-6677 4700);
DISPLAY INVISIBLE (-6677 4700);
FORCEPROP 2 LAST CDS_LIB standard
J 0
(-6675 4700);
DISPLAY INVISIBLE (-6675 4700);
FORCEADD TAP..6
(-6675 4500);
FORCEPROP 3 LASTPIN (-6625 4500) SIG_NAME P5E_CPU0_P0_RX_DP<13>
J 0
(-6615 4510);
DISPLAY 0.659574 (-6615 4510);
PAINT MONO (-6615 4510);
DISPLAY INVISIBLE (-6615 4510);
FORCEPROP 1 LASTPIN (-6625 4500) BN 13
J 0
(-6677 4508);
DISPLAY 0.680851 (-6677 4508);
PAINT MONO (-6677 4508);
FORCEPROP 1 LAST HDL_TAP TRUE
J 0
(-6350 4375);
DISPLAY 0.574468 (-6350 4375);
PAINT GREEN (-6350 4375);
DISPLAY INVISIBLE (-6350 4375);
FORCEPROP 1 LAST BODY_TYPE PLUMBING
J 0
(-6675 4450);
DISPLAY 0.574468 (-6675 4450);
PAINT GREEN (-6675 4450);
DISPLAY INVISIBLE (-6675 4450);
FORCEPROP 1 LAST PATH I348
J 0
(-6677 4500);
DISPLAY 0.872340 (-6677 4500);
PAINT GREEN (-6677 4500);
DISPLAY INVISIBLE (-6677 4500);
FORCEPROP 2 LAST CDS_LIB standard
J 0
(-6675 4500);
DISPLAY INVISIBLE (-6675 4500);
FORCEADD TAP..6
(-6675 4600);
FORCEPROP 3 LASTPIN (-6625 4600) SIG_NAME P5E_CPU0_P0_RX_DP<12>
J 0
(-6615 4610);
DISPLAY 0.659574 (-6615 4610);
PAINT MONO (-6615 4610);
DISPLAY INVISIBLE (-6615 4610);
FORCEPROP 1 LASTPIN (-6625 4600) BN 12
J 0
(-6677 4608);
DISPLAY 0.680851 (-6677 4608);
PAINT MONO (-6677 4608);
FORCEPROP 1 LAST HDL_TAP TRUE
J 0
(-6350 4475);
DISPLAY 0.574468 (-6350 4475);
PAINT GREEN (-6350 4475);
DISPLAY INVISIBLE (-6350 4475);
FORCEPROP 1 LAST BODY_TYPE PLUMBING
J 0
(-6675 4550);
DISPLAY 0.574468 (-6675 4550);
PAINT GREEN (-6675 4550);
DISPLAY INVISIBLE (-6675 4550);
FORCEPROP 1 LAST PATH I349
J 0
(-6677 4600);
DISPLAY 0.872340 (-6677 4600);
PAINT GREEN (-6677 4600);
DISPLAY INVISIBLE (-6677 4600);
FORCEPROP 2 LAST CDS_LIB standard
J 0
(-6675 4600);
DISPLAY INVISIBLE (-6675 4600);
FORCEADD TAP..6
(-6825 4950);
FORCEPROP 3 LASTPIN (-6775 4950) SIG_NAME P5E_CPU0_P0_RX_DN<8>
J 0
(-6765 4960);
DISPLAY 0.659574 (-6765 4960);
PAINT MONO (-6765 4960);
DISPLAY INVISIBLE (-6765 4960);
FORCEPROP 1 LASTPIN (-6775 4950) BN 8
J 0
(-6827 4958);
DISPLAY 0.680851 (-6827 4958);
PAINT MONO (-6827 4958);
FORCEPROP 1 LAST HDL_TAP TRUE
J 0
(-6500 4825);
DISPLAY 0.574468 (-6500 4825);
PAINT GREEN (-6500 4825);
DISPLAY INVISIBLE (-6500 4825);
FORCEPROP 1 LAST BODY_TYPE PLUMBING
J 0
(-6825 4900);
DISPLAY 0.574468 (-6825 4900);
PAINT GREEN (-6825 4900);
DISPLAY INVISIBLE (-6825 4900);
FORCEPROP 1 LAST PATH I350
J 0
(-6827 4950);
DISPLAY 0.872340 (-6827 4950);
PAINT GREEN (-6827 4950);
DISPLAY INVISIBLE (-6827 4950);
FORCEPROP 2 LAST CDS_LIB standard
J 0
(-6825 4950);
DISPLAY INVISIBLE (-6825 4950);
FORCEADD TAP..6
(-6825 4850);
FORCEPROP 3 LASTPIN (-6775 4850) SIG_NAME P5E_CPU0_P0_RX_DN<9>
J 0
(-6765 4860);
DISPLAY 0.659574 (-6765 4860);
PAINT MONO (-6765 4860);
DISPLAY INVISIBLE (-6765 4860);
FORCEPROP 1 LASTPIN (-6775 4850) BN 9
J 0
(-6827 4858);
DISPLAY 0.680851 (-6827 4858);
PAINT MONO (-6827 4858);
FORCEPROP 1 LAST HDL_TAP TRUE
J 0
(-6500 4725);
DISPLAY 0.574468 (-6500 4725);
PAINT GREEN (-6500 4725);
DISPLAY INVISIBLE (-6500 4725);
FORCEPROP 1 LAST BODY_TYPE PLUMBING
J 0
(-6825 4800);
DISPLAY 0.574468 (-6825 4800);
PAINT GREEN (-6825 4800);
DISPLAY INVISIBLE (-6825 4800);
FORCEPROP 1 LAST PATH I351
J 0
(-6827 4850);
DISPLAY 0.872340 (-6827 4850);
PAINT GREEN (-6827 4850);
DISPLAY INVISIBLE (-6827 4850);
FORCEPROP 2 LAST CDS_LIB standard
J 0
(-6825 4850);
DISPLAY INVISIBLE (-6825 4850);
FORCEADD TAP..6
(-6825 4750);
FORCEPROP 3 LASTPIN (-6775 4750) SIG_NAME P5E_CPU0_P0_RX_DN<10>
J 0
(-6765 4760);
DISPLAY 0.659574 (-6765 4760);
PAINT MONO (-6765 4760);
DISPLAY INVISIBLE (-6765 4760);
FORCEPROP 1 LASTPIN (-6775 4750) BN 10
J 0
(-6827 4758);
DISPLAY 0.680851 (-6827 4758);
PAINT MONO (-6827 4758);
FORCEPROP 1 LAST HDL_TAP TRUE
J 0
(-6500 4625);
DISPLAY 0.574468 (-6500 4625);
PAINT GREEN (-6500 4625);
DISPLAY INVISIBLE (-6500 4625);
FORCEPROP 1 LAST BODY_TYPE PLUMBING
J 0
(-6825 4700);
DISPLAY 0.574468 (-6825 4700);
PAINT GREEN (-6825 4700);
DISPLAY INVISIBLE (-6825 4700);
FORCEPROP 1 LAST PATH I352
J 0
(-6827 4750);
DISPLAY 0.872340 (-6827 4750);
PAINT GREEN (-6827 4750);
DISPLAY INVISIBLE (-6827 4750);
FORCEPROP 2 LAST CDS_LIB standard
J 0
(-6825 4750);
DISPLAY INVISIBLE (-6825 4750);
FORCEADD TAP..6
(-6825 4650);
FORCEPROP 3 LASTPIN (-6775 4650) SIG_NAME P5E_CPU0_P0_RX_DN<11>
J 0
(-6765 4660);
DISPLAY 0.659574 (-6765 4660);
PAINT MONO (-6765 4660);
DISPLAY INVISIBLE (-6765 4660);
FORCEPROP 1 LASTPIN (-6775 4650) BN 11
J 0
(-6827 4658);
DISPLAY 0.680851 (-6827 4658);
PAINT MONO (-6827 4658);
FORCEPROP 1 LAST HDL_TAP TRUE
J 0
(-6500 4525);
DISPLAY 0.574468 (-6500 4525);
PAINT GREEN (-6500 4525);
DISPLAY INVISIBLE (-6500 4525);
FORCEPROP 1 LAST BODY_TYPE PLUMBING
J 0
(-6825 4600);
DISPLAY 0.574468 (-6825 4600);
PAINT GREEN (-6825 4600);
DISPLAY INVISIBLE (-6825 4600);
FORCEPROP 1 LAST PATH I353
J 0
(-6827 4650);
DISPLAY 0.872340 (-6827 4650);
PAINT GREEN (-6827 4650);
DISPLAY INVISIBLE (-6827 4650);
FORCEPROP 2 LAST CDS_LIB standard
J 0
(-6825 4650);
DISPLAY INVISIBLE (-6825 4650);
FORCEADD TAP..6
(-6825 4550);
FORCEPROP 3 LASTPIN (-6775 4550) SIG_NAME P5E_CPU0_P0_RX_DN<12>
J 0
(-6765 4560);
DISPLAY 0.659574 (-6765 4560);
PAINT MONO (-6765 4560);
DISPLAY INVISIBLE (-6765 4560);
FORCEPROP 1 LASTPIN (-6775 4550) BN 12
J 0
(-6827 4558);
DISPLAY 0.680851 (-6827 4558);
PAINT MONO (-6827 4558);
FORCEPROP 1 LAST HDL_TAP TRUE
J 0
(-6500 4425);
DISPLAY 0.574468 (-6500 4425);
PAINT GREEN (-6500 4425);
DISPLAY INVISIBLE (-6500 4425);
FORCEPROP 1 LAST BODY_TYPE PLUMBING
J 0
(-6825 4500);
DISPLAY 0.574468 (-6825 4500);
PAINT GREEN (-6825 4500);
DISPLAY INVISIBLE (-6825 4500);
FORCEPROP 1 LAST PATH I354
J 0
(-6827 4550);
DISPLAY 0.872340 (-6827 4550);
PAINT GREEN (-6827 4550);
DISPLAY INVISIBLE (-6827 4550);
FORCEPROP 2 LAST CDS_LIB standard
J 0
(-6825 4550);
DISPLAY INVISIBLE (-6825 4550);
FORCEADD TAP..6
(-6675 4400);
FORCEPROP 3 LASTPIN (-6625 4400) SIG_NAME P5E_CPU0_P0_RX_DP<14>
J 0
(-6615 4410);
DISPLAY 0.659574 (-6615 4410);
PAINT MONO (-6615 4410);
DISPLAY INVISIBLE (-6615 4410);
FORCEPROP 1 LASTPIN (-6625 4400) BN 14
J 0
(-6677 4408);
DISPLAY 0.680851 (-6677 4408);
PAINT MONO (-6677 4408);
FORCEPROP 1 LAST HDL_TAP TRUE
J 0
(-6350 4275);
DISPLAY 0.574468 (-6350 4275);
PAINT GREEN (-6350 4275);
DISPLAY INVISIBLE (-6350 4275);
FORCEPROP 1 LAST BODY_TYPE PLUMBING
J 0
(-6675 4350);
DISPLAY 0.574468 (-6675 4350);
PAINT GREEN (-6675 4350);
DISPLAY INVISIBLE (-6675 4350);
FORCEPROP 1 LAST PATH I355
J 0
(-6677 4400);
DISPLAY 0.872340 (-6677 4400);
PAINT GREEN (-6677 4400);
DISPLAY INVISIBLE (-6677 4400);
FORCEPROP 2 LAST CDS_LIB standard
J 0
(-6675 4400);
DISPLAY INVISIBLE (-6675 4400);
FORCEADD TAP..6
(-6825 4250);
FORCEPROP 3 LASTPIN (-6775 4250) SIG_NAME P5E_CPU0_P0_RX_DN<15>
J 0
(-6765 4260);
DISPLAY 0.659574 (-6765 4260);
PAINT MONO (-6765 4260);
DISPLAY INVISIBLE (-6765 4260);
FORCEPROP 1 LASTPIN (-6775 4250) BN 15
J 0
(-6827 4258);
DISPLAY 0.680851 (-6827 4258);
PAINT MONO (-6827 4258);
FORCEPROP 1 LAST HDL_TAP TRUE
J 0
(-6500 4125);
DISPLAY 0.574468 (-6500 4125);
PAINT GREEN (-6500 4125);
DISPLAY INVISIBLE (-6500 4125);
FORCEPROP 1 LAST BODY_TYPE PLUMBING
J 0
(-6825 4200);
DISPLAY 0.574468 (-6825 4200);
PAINT GREEN (-6825 4200);
DISPLAY INVISIBLE (-6825 4200);
FORCEPROP 1 LAST PATH I356
J 0
(-6827 4250);
DISPLAY 0.872340 (-6827 4250);
PAINT GREEN (-6827 4250);
DISPLAY INVISIBLE (-6827 4250);
FORCEPROP 2 LAST CDS_LIB standard
J 0
(-6825 4250);
DISPLAY INVISIBLE (-6825 4250);
FORCEADD TAP..6
(-6825 4350);
FORCEPROP 3 LASTPIN (-6775 4350) SIG_NAME P5E_CPU0_P0_RX_DN<14>
J 0
(-6765 4360);
DISPLAY 0.659574 (-6765 4360);
PAINT MONO (-6765 4360);
DISPLAY INVISIBLE (-6765 4360);
FORCEPROP 1 LASTPIN (-6775 4350) BN 14
J 0
(-6827 4358);
DISPLAY 0.680851 (-6827 4358);
PAINT MONO (-6827 4358);
FORCEPROP 1 LAST HDL_TAP TRUE
J 0
(-6500 4225);
DISPLAY 0.574468 (-6500 4225);
PAINT GREEN (-6500 4225);
DISPLAY INVISIBLE (-6500 4225);
FORCEPROP 1 LAST BODY_TYPE PLUMBING
J 0
(-6825 4300);
DISPLAY 0.574468 (-6825 4300);
PAINT GREEN (-6825 4300);
DISPLAY INVISIBLE (-6825 4300);
FORCEPROP 1 LAST PATH I357
J 0
(-6827 4350);
DISPLAY 0.872340 (-6827 4350);
PAINT GREEN (-6827 4350);
DISPLAY INVISIBLE (-6827 4350);
FORCEPROP 2 LAST CDS_LIB standard
J 0
(-6825 4350);
DISPLAY INVISIBLE (-6825 4350);
FORCEADD OFFPAGE..1
(-8050 5975);
FORCEPROP 1 LAST COMMENT_BODY TRUE
J 0
(-7925 5875);
DISPLAY 0.872340 (-7925 5875);
PAINT GREEN (-7925 5875);
DISPLAY INVISIBLE (-7925 5875);
FORCEPROP 1 LAST OFFPAGE TRUE
J 0
(-7725 5850);
DISPLAY 0.872340 (-7725 5850);
PAINT GREEN (-7725 5850);
DISPLAY INVISIBLE (-7725 5850);
FORCEPROP 2 LAST PATH I358
J 0
(-8000 6050);
DISPLAY 0.680851 (-8000 6050);
DISPLAY INVISIBLE (-8000 6050);
FORCEPROP 2 LAST CDS_LIB standard
J 0
(-8050 5975);
DISPLAY INVISIBLE (-8050 5975);
FORCEADD OFFPAGE..1
(-8050 6025);
FORCEPROP 1 LAST COMMENT_BODY TRUE
J 0
(-7925 5925);
DISPLAY 0.872340 (-7925 5925);
PAINT GREEN (-7925 5925);
DISPLAY INVISIBLE (-7925 5925);
FORCEPROP 1 LAST OFFPAGE TRUE
J 0
(-7725 5900);
DISPLAY 0.872340 (-7725 5900);
PAINT GREEN (-7725 5900);
DISPLAY INVISIBLE (-7725 5900);
FORCEPROP 2 LAST PATH I359
J 0
(-8000 6100);
DISPLAY 0.680851 (-8000 6100);
DISPLAY INVISIBLE (-8000 6100);
FORCEPROP 2 LAST CDS_LIB standard
J 0
(-8050 6025);
DISPLAY INVISIBLE (-8050 6025);
FORCEADD TAP..6
R 2
(-3100 5750);
FORCEPROP 3 LASTPIN (-3150 5750) SIG_NAME P5E_CPU0_P0_TX_DN<0>
J 0
(-3140 5760);
DISPLAY 0.659574 (-3140 5760);
PAINT MONO (-3140 5760);
DISPLAY INVISIBLE (-3140 5760);
FORCEPROP 1 LASTPIN (-3150 5750) BN 0
J 2
(-3098 5758);
DISPLAY 0.680851 (-3098 5758);
PAINT MONO (-3098 5758);
FORCEPROP 2 LAST ROOM RISER1
J 0
(-3600 5800);
DISPLAY 0.829787 (-3600 5800);
PAINT RED (-3600 5800);
DISPLAY INVISIBLE (-3600 5800);
FORCEPROP 1 LAST HDL_TAP TRUE
J 2
(-3425 5625);
DISPLAY 0.702128 (-3425 5625);
PAINT GREEN (-3425 5625);
DISPLAY INVISIBLE (-3425 5625);
FORCEPROP 1 LAST BODY_TYPE PLUMBING
J 2
(-3100 5700);
DISPLAY 0.702128 (-3100 5700);
PAINT GREEN (-3100 5700);
DISPLAY INVISIBLE (-3100 5700);
FORCEPROP 2 LAST BOM_COST IO_SLOT
J 0
(-3600 5850);
DISPLAY 0.829787 (-3600 5850);
DISPLAY INVISIBLE (-3600 5850);
FORCEPROP 1 LAST PATH I360
J 2
(-3098 5750);
DISPLAY 0.872340 (-3098 5750);
PAINT GREEN (-3098 5750);
DISPLAY INVISIBLE (-3098 5750);
FORCEPROP 2 LAST CDS_LIB mstr_standard
J 0
(-3100 5750);
DISPLAY INVISIBLE (-3100 5750);
FORCEADD TAP..6
R 2
(-3100 5650);
FORCEPROP 3 LASTPIN (-3150 5650) SIG_NAME P5E_CPU0_P0_TX_DN<1>
J 0
(-3140 5660);
DISPLAY 0.659574 (-3140 5660);
PAINT MONO (-3140 5660);
DISPLAY INVISIBLE (-3140 5660);
FORCEPROP 1 LASTPIN (-3150 5650) BN 1
J 2
(-3098 5658);
DISPLAY 0.680851 (-3098 5658);
PAINT MONO (-3098 5658);
FORCEPROP 2 LAST ROOM RISER1
J 0
(-3600 5700);
DISPLAY 0.829787 (-3600 5700);
PAINT RED (-3600 5700);
DISPLAY INVISIBLE (-3600 5700);
FORCEPROP 1 LAST HDL_TAP TRUE
J 2
(-3425 5525);
DISPLAY 0.702128 (-3425 5525);
PAINT GREEN (-3425 5525);
DISPLAY INVISIBLE (-3425 5525);
FORCEPROP 1 LAST BODY_TYPE PLUMBING
J 2
(-3100 5600);
DISPLAY 0.702128 (-3100 5600);
PAINT GREEN (-3100 5600);
DISPLAY INVISIBLE (-3100 5600);
FORCEPROP 2 LAST BOM_COST IO_SLOT
J 0
(-3600 5750);
DISPLAY 0.829787 (-3600 5750);
DISPLAY INVISIBLE (-3600 5750);
FORCEPROP 1 LAST PATH I361
J 2
(-3098 5650);
DISPLAY 0.872340 (-3098 5650);
PAINT GREEN (-3098 5650);
DISPLAY INVISIBLE (-3098 5650);
FORCEPROP 2 LAST CDS_LIB mstr_standard
J 0
(-3100 5650);
DISPLAY INVISIBLE (-3100 5650);
FORCEADD TAP..6
R 2
(-3100 5550);
FORCEPROP 3 LASTPIN (-3150 5550) SIG_NAME P5E_CPU0_P0_TX_DN<2>
J 0
(-3140 5560);
DISPLAY 0.659574 (-3140 5560);
PAINT MONO (-3140 5560);
DISPLAY INVISIBLE (-3140 5560);
FORCEPROP 1 LASTPIN (-3150 5550) BN 2
J 2
(-3098 5558);
DISPLAY 0.680851 (-3098 5558);
PAINT MONO (-3098 5558);
FORCEPROP 2 LAST ROOM RISER1
J 0
(-3600 5600);
DISPLAY 0.829787 (-3600 5600);
PAINT RED (-3600 5600);
DISPLAY INVISIBLE (-3600 5600);
FORCEPROP 1 LAST HDL_TAP TRUE
J 2
(-3425 5425);
DISPLAY 0.702128 (-3425 5425);
PAINT GREEN (-3425 5425);
DISPLAY INVISIBLE (-3425 5425);
FORCEPROP 1 LAST BODY_TYPE PLUMBING
J 2
(-3100 5500);
DISPLAY 0.702128 (-3100 5500);
PAINT GREEN (-3100 5500);
DISPLAY INVISIBLE (-3100 5500);
FORCEPROP 2 LAST BOM_COST IO_SLOT
J 0
(-3600 5650);
DISPLAY 0.829787 (-3600 5650);
DISPLAY INVISIBLE (-3600 5650);
FORCEPROP 1 LAST PATH I362
J 2
(-3098 5550);
DISPLAY 0.872340 (-3098 5550);
PAINT GREEN (-3098 5550);
DISPLAY INVISIBLE (-3098 5550);
FORCEPROP 2 LAST CDS_LIB standard
J 0
(-3100 5550);
DISPLAY INVISIBLE (-3100 5550);
FORCEADD TAP..6
R 2
(-3250 5700);
FORCEPROP 3 LASTPIN (-3300 5700) SIG_NAME P5E_CPU0_P0_TX_DP<1>
J 0
(-3290 5710);
DISPLAY 0.659574 (-3290 5710);
PAINT MONO (-3290 5710);
DISPLAY INVISIBLE (-3290 5710);
FORCEPROP 1 LASTPIN (-3300 5700) BN 1
J 2
(-3248 5708);
DISPLAY 0.680851 (-3248 5708);
PAINT MONO (-3248 5708);
FORCEPROP 2 LAST ROOM RISER1
J 0
(-3750 5750);
DISPLAY 0.829787 (-3750 5750);
PAINT RED (-3750 5750);
DISPLAY INVISIBLE (-3750 5750);
FORCEPROP 1 LAST HDL_TAP TRUE
J 2
(-3575 5575);
DISPLAY 0.702128 (-3575 5575);
PAINT GREEN (-3575 5575);
DISPLAY INVISIBLE (-3575 5575);
FORCEPROP 1 LAST BODY_TYPE PLUMBING
J 2
(-3250 5650);
DISPLAY 0.702128 (-3250 5650);
PAINT GREEN (-3250 5650);
DISPLAY INVISIBLE (-3250 5650);
FORCEPROP 2 LAST BOM_COST IO_SLOT
J 0
(-3750 5800);
DISPLAY 0.829787 (-3750 5800);
DISPLAY INVISIBLE (-3750 5800);
FORCEPROP 1 LAST PATH I363
J 2
(-3248 5700);
DISPLAY 0.872340 (-3248 5700);
PAINT GREEN (-3248 5700);
DISPLAY INVISIBLE (-3248 5700);
FORCEPROP 2 LAST CDS_LIB mstr_standard
J 0
(-3250 5700);
DISPLAY INVISIBLE (-3250 5700);
FORCEADD TAP..6
R 2
(-3250 5800);
FORCEPROP 3 LASTPIN (-3300 5800) SIG_NAME P5E_CPU0_P0_TX_DP<0>
J 0
(-3290 5810);
DISPLAY 0.659574 (-3290 5810);
PAINT MONO (-3290 5810);
DISPLAY INVISIBLE (-3290 5810);
FORCEPROP 1 LASTPIN (-3300 5800) BN 0
J 2
(-3248 5808);
DISPLAY 0.680851 (-3248 5808);
PAINT MONO (-3248 5808);
FORCEPROP 2 LAST ROOM RISER1
J 0
(-3750 5850);
DISPLAY 0.829787 (-3750 5850);
PAINT RED (-3750 5850);
DISPLAY INVISIBLE (-3750 5850);
FORCEPROP 1 LAST HDL_TAP TRUE
J 2
(-3575 5675);
DISPLAY 0.702128 (-3575 5675);
PAINT GREEN (-3575 5675);
DISPLAY INVISIBLE (-3575 5675);
FORCEPROP 1 LAST BODY_TYPE PLUMBING
J 2
(-3250 5750);
DISPLAY 0.702128 (-3250 5750);
PAINT GREEN (-3250 5750);
DISPLAY INVISIBLE (-3250 5750);
FORCEPROP 2 LAST BOM_COST IO_SLOT
J 0
(-3750 5900);
DISPLAY 0.829787 (-3750 5900);
DISPLAY INVISIBLE (-3750 5900);
FORCEPROP 1 LAST PATH I364
J 2
(-3248 5800);
DISPLAY 0.872340 (-3248 5800);
PAINT GREEN (-3248 5800);
DISPLAY INVISIBLE (-3248 5800);
FORCEPROP 2 LAST CDS_LIB mstr_standard
J 0
(-3250 5800);
DISPLAY INVISIBLE (-3250 5800);
FORCEADD TAP..6
R 2
(-3250 5600);
FORCEPROP 3 LASTPIN (-3300 5600) SIG_NAME P5E_CPU0_P0_TX_DP<2>
J 0
(-3290 5610);
DISPLAY 0.659574 (-3290 5610);
PAINT MONO (-3290 5610);
DISPLAY INVISIBLE (-3290 5610);
FORCEPROP 1 LASTPIN (-3300 5600) BN 2
J 2
(-3248 5608);
DISPLAY 0.680851 (-3248 5608);
PAINT MONO (-3248 5608);
FORCEPROP 2 LAST ROOM RISER1
J 0
(-3750 5650);
DISPLAY 0.829787 (-3750 5650);
PAINT RED (-3750 5650);
DISPLAY INVISIBLE (-3750 5650);
FORCEPROP 1 LAST HDL_TAP TRUE
J 2
(-3575 5475);
DISPLAY 0.702128 (-3575 5475);
PAINT GREEN (-3575 5475);
DISPLAY INVISIBLE (-3575 5475);
FORCEPROP 1 LAST BODY_TYPE PLUMBING
J 2
(-3250 5550);
DISPLAY 0.702128 (-3250 5550);
PAINT GREEN (-3250 5550);
DISPLAY INVISIBLE (-3250 5550);
FORCEPROP 2 LAST BOM_COST IO_SLOT
J 0
(-3750 5700);
DISPLAY 0.829787 (-3750 5700);
DISPLAY INVISIBLE (-3750 5700);
FORCEPROP 1 LAST PATH I365
J 2
(-3248 5600);
DISPLAY 0.872340 (-3248 5600);
PAINT GREEN (-3248 5600);
DISPLAY INVISIBLE (-3248 5600);
FORCEPROP 2 LAST CDS_LIB standard
J 0
(-3250 5600);
DISPLAY INVISIBLE (-3250 5600);
FORCEADD TAP..6
R 2
(-3100 5450);
FORCEPROP 3 LASTPIN (-3150 5450) SIG_NAME P5E_CPU0_P0_TX_DN<3>
J 0
(-3140 5460);
DISPLAY 0.659574 (-3140 5460);
PAINT MONO (-3140 5460);
DISPLAY INVISIBLE (-3140 5460);
FORCEPROP 1 LASTPIN (-3150 5450) BN 3
J 2
(-3098 5458);
DISPLAY 0.680851 (-3098 5458);
PAINT MONO (-3098 5458);
FORCEPROP 2 LAST ROOM RISER1
J 0
(-3600 5500);
DISPLAY 0.829787 (-3600 5500);
PAINT RED (-3600 5500);
DISPLAY INVISIBLE (-3600 5500);
FORCEPROP 1 LAST HDL_TAP TRUE
J 2
(-3425 5325);
DISPLAY 0.702128 (-3425 5325);
PAINT GREEN (-3425 5325);
DISPLAY INVISIBLE (-3425 5325);
FORCEPROP 1 LAST BODY_TYPE PLUMBING
J 2
(-3100 5400);
DISPLAY 0.702128 (-3100 5400);
PAINT GREEN (-3100 5400);
DISPLAY INVISIBLE (-3100 5400);
FORCEPROP 2 LAST BOM_COST IO_SLOT
J 0
(-3600 5550);
DISPLAY 0.829787 (-3600 5550);
DISPLAY INVISIBLE (-3600 5550);
FORCEPROP 1 LAST PATH I366
J 2
(-3098 5450);
DISPLAY 0.872340 (-3098 5450);
PAINT GREEN (-3098 5450);
DISPLAY INVISIBLE (-3098 5450);
FORCEPROP 2 LAST CDS_LIB standard
J 0
(-3100 5450);
DISPLAY INVISIBLE (-3100 5450);
FORCEADD TAP..6
R 2
(-3100 5350);
FORCEPROP 3 LASTPIN (-3150 5350) SIG_NAME P5E_CPU0_P0_TX_DN<4>
J 0
(-3140 5360);
DISPLAY 0.659574 (-3140 5360);
PAINT MONO (-3140 5360);
DISPLAY INVISIBLE (-3140 5360);
FORCEPROP 1 LASTPIN (-3150 5350) BN 4
J 2
(-3098 5358);
DISPLAY 0.680851 (-3098 5358);
PAINT MONO (-3098 5358);
FORCEPROP 2 LAST ROOM RISER1
J 0
(-3600 5400);
DISPLAY 0.829787 (-3600 5400);
PAINT RED (-3600 5400);
DISPLAY INVISIBLE (-3600 5400);
FORCEPROP 1 LAST HDL_TAP TRUE
J 2
(-3425 5225);
DISPLAY 0.702128 (-3425 5225);
PAINT GREEN (-3425 5225);
DISPLAY INVISIBLE (-3425 5225);
FORCEPROP 1 LAST BODY_TYPE PLUMBING
J 2
(-3100 5300);
DISPLAY 0.702128 (-3100 5300);
PAINT GREEN (-3100 5300);
DISPLAY INVISIBLE (-3100 5300);
FORCEPROP 2 LAST BOM_COST IO_SLOT
J 0
(-3600 5450);
DISPLAY 0.829787 (-3600 5450);
DISPLAY INVISIBLE (-3600 5450);
FORCEPROP 1 LAST PATH I367
J 2
(-3098 5350);
DISPLAY 0.872340 (-3098 5350);
PAINT GREEN (-3098 5350);
DISPLAY INVISIBLE (-3098 5350);
FORCEPROP 2 LAST CDS_LIB standard
J 0
(-3100 5350);
DISPLAY INVISIBLE (-3100 5350);
FORCEADD TAP..6
R 2
(-3100 5150);
FORCEPROP 3 LASTPIN (-3150 5150) SIG_NAME P5E_CPU0_P0_TX_DN<6>
J 0
(-3140 5160);
DISPLAY 0.659574 (-3140 5160);
PAINT MONO (-3140 5160);
DISPLAY INVISIBLE (-3140 5160);
FORCEPROP 1 LASTPIN (-3150 5150) BN 6
J 2
(-3098 5158);
DISPLAY 0.680851 (-3098 5158);
PAINT MONO (-3098 5158);
FORCEPROP 2 LAST ROOM RISER1
J 0
(-3600 5200);
DISPLAY 0.829787 (-3600 5200);
PAINT RED (-3600 5200);
DISPLAY INVISIBLE (-3600 5200);
FORCEPROP 1 LAST HDL_TAP TRUE
J 2
(-3425 5025);
DISPLAY 0.702128 (-3425 5025);
PAINT GREEN (-3425 5025);
DISPLAY INVISIBLE (-3425 5025);
FORCEPROP 1 LAST BODY_TYPE PLUMBING
J 2
(-3100 5100);
DISPLAY 0.702128 (-3100 5100);
PAINT GREEN (-3100 5100);
DISPLAY INVISIBLE (-3100 5100);
FORCEPROP 2 LAST BOM_COST IO_SLOT
J 0
(-3600 5250);
DISPLAY 0.829787 (-3600 5250);
DISPLAY INVISIBLE (-3600 5250);
FORCEPROP 1 LAST PATH I368
J 2
(-3098 5150);
DISPLAY 0.872340 (-3098 5150);
PAINT GREEN (-3098 5150);
DISPLAY INVISIBLE (-3098 5150);
FORCEPROP 2 LAST CDS_LIB standard
J 0
(-3100 5150);
DISPLAY INVISIBLE (-3100 5150);
FORCEADD TAP..6
R 2
(-3100 5250);
FORCEPROP 3 LASTPIN (-3150 5250) SIG_NAME P5E_CPU0_P0_TX_DN<5>
J 0
(-3140 5260);
DISPLAY 0.659574 (-3140 5260);
PAINT MONO (-3140 5260);
DISPLAY INVISIBLE (-3140 5260);
FORCEPROP 1 LASTPIN (-3150 5250) BN 5
J 2
(-3098 5258);
DISPLAY 0.680851 (-3098 5258);
PAINT MONO (-3098 5258);
FORCEPROP 2 LAST ROOM RISER1
J 0
(-3600 5300);
DISPLAY 0.829787 (-3600 5300);
PAINT RED (-3600 5300);
DISPLAY INVISIBLE (-3600 5300);
FORCEPROP 1 LAST HDL_TAP TRUE
J 2
(-3425 5125);
DISPLAY 0.702128 (-3425 5125);
PAINT GREEN (-3425 5125);
DISPLAY INVISIBLE (-3425 5125);
FORCEPROP 1 LAST BODY_TYPE PLUMBING
J 2
(-3100 5200);
DISPLAY 0.702128 (-3100 5200);
PAINT GREEN (-3100 5200);
DISPLAY INVISIBLE (-3100 5200);
FORCEPROP 2 LAST BOM_COST IO_SLOT
J 0
(-3600 5350);
DISPLAY 0.829787 (-3600 5350);
DISPLAY INVISIBLE (-3600 5350);
FORCEPROP 1 LAST PATH I369
J 2
(-3098 5250);
DISPLAY 0.872340 (-3098 5250);
PAINT GREEN (-3098 5250);
DISPLAY INVISIBLE (-3098 5250);
FORCEPROP 2 LAST CDS_LIB standard
J 0
(-3100 5250);
DISPLAY INVISIBLE (-3100 5250);
FORCEADD TAP..6
R 2
(-3100 5050);
FORCEPROP 3 LASTPIN (-3150 5050) SIG_NAME P5E_CPU0_P0_TX_DN<7>
J 0
(-3140 5060);
DISPLAY 0.659574 (-3140 5060);
PAINT MONO (-3140 5060);
DISPLAY INVISIBLE (-3140 5060);
FORCEPROP 1 LASTPIN (-3150 5050) BN 7
J 2
(-3098 5058);
DISPLAY 0.680851 (-3098 5058);
PAINT MONO (-3098 5058);
FORCEPROP 2 LAST ROOM RISER1
J 0
(-3600 5100);
DISPLAY 0.829787 (-3600 5100);
PAINT RED (-3600 5100);
DISPLAY INVISIBLE (-3600 5100);
FORCEPROP 1 LAST HDL_TAP TRUE
J 2
(-3425 4925);
DISPLAY 0.702128 (-3425 4925);
PAINT GREEN (-3425 4925);
DISPLAY INVISIBLE (-3425 4925);
FORCEPROP 1 LAST BODY_TYPE PLUMBING
J 2
(-3100 5000);
DISPLAY 0.702128 (-3100 5000);
PAINT GREEN (-3100 5000);
DISPLAY INVISIBLE (-3100 5000);
FORCEPROP 2 LAST BOM_COST IO_SLOT
J 0
(-3600 5150);
DISPLAY 0.829787 (-3600 5150);
DISPLAY INVISIBLE (-3600 5150);
FORCEPROP 1 LAST PATH I370
J 2
(-3098 5050);
DISPLAY 0.872340 (-3098 5050);
PAINT GREEN (-3098 5050);
DISPLAY INVISIBLE (-3098 5050);
FORCEPROP 2 LAST CDS_LIB standard
J 0
(-3100 5050);
DISPLAY INVISIBLE (-3100 5050);
FORCEADD TAP..6
R 2
(-3250 5300);
FORCEPROP 3 LASTPIN (-3300 5300) SIG_NAME P5E_CPU0_P0_TX_DP<5>
J 0
(-3290 5310);
DISPLAY 0.659574 (-3290 5310);
PAINT MONO (-3290 5310);
DISPLAY INVISIBLE (-3290 5310);
FORCEPROP 1 LASTPIN (-3300 5300) BN 5
J 2
(-3248 5308);
DISPLAY 0.680851 (-3248 5308);
PAINT MONO (-3248 5308);
FORCEPROP 2 LAST ROOM RISER1
J 0
(-3750 5350);
DISPLAY 0.829787 (-3750 5350);
PAINT RED (-3750 5350);
DISPLAY INVISIBLE (-3750 5350);
FORCEPROP 1 LAST HDL_TAP TRUE
J 2
(-3575 5175);
DISPLAY 0.702128 (-3575 5175);
PAINT GREEN (-3575 5175);
DISPLAY INVISIBLE (-3575 5175);
FORCEPROP 1 LAST BODY_TYPE PLUMBING
J 2
(-3250 5250);
DISPLAY 0.702128 (-3250 5250);
PAINT GREEN (-3250 5250);
DISPLAY INVISIBLE (-3250 5250);
FORCEPROP 2 LAST BOM_COST IO_SLOT
J 0
(-3750 5400);
DISPLAY 0.829787 (-3750 5400);
DISPLAY INVISIBLE (-3750 5400);
FORCEPROP 1 LAST PATH I371
J 2
(-3248 5300);
DISPLAY 0.872340 (-3248 5300);
PAINT GREEN (-3248 5300);
DISPLAY INVISIBLE (-3248 5300);
FORCEPROP 2 LAST CDS_LIB standard
J 0
(-3250 5300);
DISPLAY INVISIBLE (-3250 5300);
FORCEADD TAP..6
R 2
(-3250 5400);
FORCEPROP 3 LASTPIN (-3300 5400) SIG_NAME P5E_CPU0_P0_TX_DP<4>
J 0
(-3290 5410);
DISPLAY 0.659574 (-3290 5410);
PAINT MONO (-3290 5410);
DISPLAY INVISIBLE (-3290 5410);
FORCEPROP 1 LASTPIN (-3300 5400) BN 4
J 2
(-3248 5408);
DISPLAY 0.680851 (-3248 5408);
PAINT MONO (-3248 5408);
FORCEPROP 2 LAST ROOM RISER1
J 0
(-3750 5450);
DISPLAY 0.829787 (-3750 5450);
PAINT RED (-3750 5450);
DISPLAY INVISIBLE (-3750 5450);
FORCEPROP 1 LAST HDL_TAP TRUE
J 2
(-3575 5275);
DISPLAY 0.702128 (-3575 5275);
PAINT GREEN (-3575 5275);
DISPLAY INVISIBLE (-3575 5275);
FORCEPROP 1 LAST BODY_TYPE PLUMBING
J 2
(-3250 5350);
DISPLAY 0.702128 (-3250 5350);
PAINT GREEN (-3250 5350);
DISPLAY INVISIBLE (-3250 5350);
FORCEPROP 2 LAST BOM_COST IO_SLOT
J 0
(-3750 5500);
DISPLAY 0.829787 (-3750 5500);
DISPLAY INVISIBLE (-3750 5500);
FORCEPROP 1 LAST PATH I372
J 2
(-3248 5400);
DISPLAY 0.872340 (-3248 5400);
PAINT GREEN (-3248 5400);
DISPLAY INVISIBLE (-3248 5400);
FORCEPROP 2 LAST CDS_LIB standard
J 0
(-3250 5400);
DISPLAY INVISIBLE (-3250 5400);
FORCEADD TAP..6
R 2
(-3250 5500);
FORCEPROP 3 LASTPIN (-3300 5500) SIG_NAME P5E_CPU0_P0_TX_DP<3>
J 0
(-3290 5510);
DISPLAY 0.659574 (-3290 5510);
PAINT MONO (-3290 5510);
DISPLAY INVISIBLE (-3290 5510);
FORCEPROP 1 LASTPIN (-3300 5500) BN 3
J 2
(-3248 5508);
DISPLAY 0.680851 (-3248 5508);
PAINT MONO (-3248 5508);
FORCEPROP 2 LAST ROOM RISER1
J 0
(-3750 5550);
DISPLAY 0.829787 (-3750 5550);
PAINT RED (-3750 5550);
DISPLAY INVISIBLE (-3750 5550);
FORCEPROP 1 LAST HDL_TAP TRUE
J 2
(-3575 5375);
DISPLAY 0.702128 (-3575 5375);
PAINT GREEN (-3575 5375);
DISPLAY INVISIBLE (-3575 5375);
FORCEPROP 1 LAST BODY_TYPE PLUMBING
J 2
(-3250 5450);
DISPLAY 0.702128 (-3250 5450);
PAINT GREEN (-3250 5450);
DISPLAY INVISIBLE (-3250 5450);
FORCEPROP 2 LAST BOM_COST IO_SLOT
J 0
(-3750 5600);
DISPLAY 0.829787 (-3750 5600);
DISPLAY INVISIBLE (-3750 5600);
FORCEPROP 1 LAST PATH I373
J 2
(-3248 5500);
DISPLAY 0.872340 (-3248 5500);
PAINT GREEN (-3248 5500);
DISPLAY INVISIBLE (-3248 5500);
FORCEPROP 2 LAST CDS_LIB standard
J 0
(-3250 5500);
DISPLAY INVISIBLE (-3250 5500);
FORCEADD TAP..6
R 2
(-3250 5100);
FORCEPROP 3 LASTPIN (-3300 5100) SIG_NAME P5E_CPU0_P0_TX_DP<7>
J 0
(-3290 5110);
DISPLAY 0.659574 (-3290 5110);
PAINT MONO (-3290 5110);
DISPLAY INVISIBLE (-3290 5110);
FORCEPROP 1 LASTPIN (-3300 5100) BN 7
J 2
(-3248 5108);
DISPLAY 0.680851 (-3248 5108);
PAINT MONO (-3248 5108);
FORCEPROP 2 LAST ROOM RISER1
J 0
(-3750 5150);
DISPLAY 0.829787 (-3750 5150);
PAINT RED (-3750 5150);
DISPLAY INVISIBLE (-3750 5150);
FORCEPROP 1 LAST HDL_TAP TRUE
J 2
(-3575 4975);
DISPLAY 0.702128 (-3575 4975);
PAINT GREEN (-3575 4975);
DISPLAY INVISIBLE (-3575 4975);
FORCEPROP 1 LAST BODY_TYPE PLUMBING
J 2
(-3250 5050);
DISPLAY 0.702128 (-3250 5050);
PAINT GREEN (-3250 5050);
DISPLAY INVISIBLE (-3250 5050);
FORCEPROP 2 LAST BOM_COST IO_SLOT
J 0
(-3750 5200);
DISPLAY 0.829787 (-3750 5200);
DISPLAY INVISIBLE (-3750 5200);
FORCEPROP 1 LAST PATH I374
J 2
(-3248 5100);
DISPLAY 0.872340 (-3248 5100);
PAINT GREEN (-3248 5100);
DISPLAY INVISIBLE (-3248 5100);
FORCEPROP 2 LAST CDS_LIB standard
J 0
(-3250 5100);
DISPLAY INVISIBLE (-3250 5100);
FORCEADD TAP..6
R 2
(-3250 5200);
FORCEPROP 3 LASTPIN (-3300 5200) SIG_NAME P5E_CPU0_P0_TX_DP<6>
J 0
(-3290 5210);
DISPLAY 0.659574 (-3290 5210);
PAINT MONO (-3290 5210);
DISPLAY INVISIBLE (-3290 5210);
FORCEPROP 1 LASTPIN (-3300 5200) BN 6
J 2
(-3248 5208);
DISPLAY 0.680851 (-3248 5208);
PAINT MONO (-3248 5208);
FORCEPROP 2 LAST ROOM RISER1
J 0
(-3750 5250);
DISPLAY 0.829787 (-3750 5250);
PAINT RED (-3750 5250);
DISPLAY INVISIBLE (-3750 5250);
FORCEPROP 1 LAST HDL_TAP TRUE
J 2
(-3575 5075);
DISPLAY 0.702128 (-3575 5075);
PAINT GREEN (-3575 5075);
DISPLAY INVISIBLE (-3575 5075);
FORCEPROP 1 LAST BODY_TYPE PLUMBING
J 2
(-3250 5150);
DISPLAY 0.702128 (-3250 5150);
PAINT GREEN (-3250 5150);
DISPLAY INVISIBLE (-3250 5150);
FORCEPROP 2 LAST BOM_COST IO_SLOT
J 0
(-3750 5300);
DISPLAY 0.829787 (-3750 5300);
DISPLAY INVISIBLE (-3750 5300);
FORCEPROP 1 LAST PATH I375
J 2
(-3248 5200);
DISPLAY 0.872340 (-3248 5200);
PAINT GREEN (-3248 5200);
DISPLAY INVISIBLE (-3248 5200);
FORCEPROP 2 LAST CDS_LIB standard
J 0
(-3250 5200);
DISPLAY INVISIBLE (-3250 5200);
FORCEADD TAP..6
R 2
(-3100 4950);
FORCEPROP 3 LASTPIN (-3150 4950) SIG_NAME P5E_CPU0_P0_TX_DN<8>
J 0
(-3140 4960);
DISPLAY 0.659574 (-3140 4960);
PAINT MONO (-3140 4960);
DISPLAY INVISIBLE (-3140 4960);
FORCEPROP 1 LASTPIN (-3150 4950) BN 8
J 2
(-3098 4958);
DISPLAY 0.680851 (-3098 4958);
PAINT MONO (-3098 4958);
FORCEPROP 2 LAST ROOM RISER1
J 0
(-3600 5000);
DISPLAY 0.829787 (-3600 5000);
PAINT RED (-3600 5000);
DISPLAY INVISIBLE (-3600 5000);
FORCEPROP 1 LAST HDL_TAP TRUE
J 2
(-3425 4825);
DISPLAY 0.702128 (-3425 4825);
PAINT GREEN (-3425 4825);
DISPLAY INVISIBLE (-3425 4825);
FORCEPROP 1 LAST BODY_TYPE PLUMBING
J 2
(-3100 4900);
DISPLAY 0.702128 (-3100 4900);
PAINT GREEN (-3100 4900);
DISPLAY INVISIBLE (-3100 4900);
FORCEPROP 2 LAST BOM_COST IO_SLOT
J 0
(-3600 5050);
DISPLAY 0.829787 (-3600 5050);
DISPLAY INVISIBLE (-3600 5050);
FORCEPROP 1 LAST PATH I376
J 2
(-3098 4950);
DISPLAY 0.872340 (-3098 4950);
PAINT GREEN (-3098 4950);
DISPLAY INVISIBLE (-3098 4950);
FORCEPROP 2 LAST CDS_LIB standard
J 0
(-3100 4950);
DISPLAY INVISIBLE (-3100 4950);
FORCEADD TAP..6
R 2
(-3100 4850);
FORCEPROP 3 LASTPIN (-3150 4850) SIG_NAME P5E_CPU0_P0_TX_DN<9>
J 0
(-3140 4860);
DISPLAY 0.659574 (-3140 4860);
PAINT MONO (-3140 4860);
DISPLAY INVISIBLE (-3140 4860);
FORCEPROP 1 LASTPIN (-3150 4850) BN 9
J 2
(-3098 4858);
DISPLAY 0.680851 (-3098 4858);
PAINT MONO (-3098 4858);
FORCEPROP 2 LAST ROOM RISER1
J 0
(-3600 4900);
DISPLAY 0.829787 (-3600 4900);
PAINT RED (-3600 4900);
DISPLAY INVISIBLE (-3600 4900);
FORCEPROP 1 LAST HDL_TAP TRUE
J 2
(-3425 4725);
DISPLAY 0.702128 (-3425 4725);
PAINT GREEN (-3425 4725);
DISPLAY INVISIBLE (-3425 4725);
FORCEPROP 1 LAST BODY_TYPE PLUMBING
J 2
(-3100 4800);
DISPLAY 0.702128 (-3100 4800);
PAINT GREEN (-3100 4800);
DISPLAY INVISIBLE (-3100 4800);
FORCEPROP 2 LAST BOM_COST IO_SLOT
J 0
(-3600 4950);
DISPLAY 0.829787 (-3600 4950);
DISPLAY INVISIBLE (-3600 4950);
FORCEPROP 1 LAST PATH I377
J 2
(-3098 4850);
DISPLAY 0.872340 (-3098 4850);
PAINT GREEN (-3098 4850);
DISPLAY INVISIBLE (-3098 4850);
FORCEPROP 2 LAST CDS_LIB standard
J 0
(-3100 4850);
DISPLAY INVISIBLE (-3100 4850);
FORCEADD TAP..6
R 2
(-3100 4650);
FORCEPROP 3 LASTPIN (-3150 4650) SIG_NAME P5E_CPU0_P0_TX_DN<11>
J 0
(-3140 4660);
DISPLAY 0.659574 (-3140 4660);
PAINT MONO (-3140 4660);
DISPLAY INVISIBLE (-3140 4660);
FORCEPROP 1 LASTPIN (-3150 4650) BN 11
J 2
(-3098 4658);
DISPLAY 0.680851 (-3098 4658);
PAINT MONO (-3098 4658);
FORCEPROP 2 LAST ROOM RISER1
J 0
(-3600 4700);
DISPLAY 0.829787 (-3600 4700);
PAINT RED (-3600 4700);
DISPLAY INVISIBLE (-3600 4700);
FORCEPROP 1 LAST HDL_TAP TRUE
J 2
(-3425 4525);
DISPLAY 0.702128 (-3425 4525);
PAINT GREEN (-3425 4525);
DISPLAY INVISIBLE (-3425 4525);
FORCEPROP 1 LAST BODY_TYPE PLUMBING
J 2
(-3100 4600);
DISPLAY 0.702128 (-3100 4600);
PAINT GREEN (-3100 4600);
DISPLAY INVISIBLE (-3100 4600);
FORCEPROP 2 LAST BOM_COST IO_SLOT
J 0
(-3600 4750);
DISPLAY 0.829787 (-3600 4750);
DISPLAY INVISIBLE (-3600 4750);
FORCEPROP 1 LAST PATH I378
J 2
(-3098 4650);
DISPLAY 0.872340 (-3098 4650);
PAINT GREEN (-3098 4650);
DISPLAY INVISIBLE (-3098 4650);
FORCEPROP 2 LAST CDS_LIB standard
J 0
(-3100 4650);
DISPLAY INVISIBLE (-3100 4650);
FORCEADD TAP..6
R 2
(-3100 4750);
FORCEPROP 3 LASTPIN (-3150 4750) SIG_NAME P5E_CPU0_P0_TX_DN<10>
J 0
(-3140 4760);
DISPLAY 0.659574 (-3140 4760);
PAINT MONO (-3140 4760);
DISPLAY INVISIBLE (-3140 4760);
FORCEPROP 1 LASTPIN (-3150 4750) BN 10
J 2
(-3098 4758);
DISPLAY 0.680851 (-3098 4758);
PAINT MONO (-3098 4758);
FORCEPROP 2 LAST ROOM RISER1
J 0
(-3600 4800);
DISPLAY 0.829787 (-3600 4800);
PAINT RED (-3600 4800);
DISPLAY INVISIBLE (-3600 4800);
FORCEPROP 1 LAST HDL_TAP TRUE
J 2
(-3425 4625);
DISPLAY 0.702128 (-3425 4625);
PAINT GREEN (-3425 4625);
DISPLAY INVISIBLE (-3425 4625);
FORCEPROP 1 LAST BODY_TYPE PLUMBING
J 2
(-3100 4700);
DISPLAY 0.702128 (-3100 4700);
PAINT GREEN (-3100 4700);
DISPLAY INVISIBLE (-3100 4700);
FORCEPROP 2 LAST BOM_COST IO_SLOT
J 0
(-3600 4850);
DISPLAY 0.829787 (-3600 4850);
DISPLAY INVISIBLE (-3600 4850);
FORCEPROP 1 LAST PATH I379
J 2
(-3098 4750);
DISPLAY 0.872340 (-3098 4750);
PAINT GREEN (-3098 4750);
DISPLAY INVISIBLE (-3098 4750);
FORCEPROP 2 LAST CDS_LIB standard
J 0
(-3100 4750);
DISPLAY INVISIBLE (-3100 4750);
FORCEADD TAP..6
R 2
(-3100 4550);
FORCEPROP 3 LASTPIN (-3150 4550) SIG_NAME P5E_CPU0_P0_TX_DN<12>
J 0
(-3140 4560);
DISPLAY 0.659574 (-3140 4560);
PAINT MONO (-3140 4560);
DISPLAY INVISIBLE (-3140 4560);
FORCEPROP 1 LASTPIN (-3150 4550) BN 12
J 2
(-3098 4558);
DISPLAY 0.680851 (-3098 4558);
PAINT MONO (-3098 4558);
FORCEPROP 2 LAST ROOM RISER1
J 0
(-3600 4600);
DISPLAY 0.829787 (-3600 4600);
PAINT RED (-3600 4600);
DISPLAY INVISIBLE (-3600 4600);
FORCEPROP 1 LAST HDL_TAP TRUE
J 2
(-3425 4425);
DISPLAY 0.702128 (-3425 4425);
PAINT GREEN (-3425 4425);
DISPLAY INVISIBLE (-3425 4425);
FORCEPROP 1 LAST BODY_TYPE PLUMBING
J 2
(-3100 4500);
DISPLAY 0.702128 (-3100 4500);
PAINT GREEN (-3100 4500);
DISPLAY INVISIBLE (-3100 4500);
FORCEPROP 2 LAST BOM_COST IO_SLOT
J 0
(-3600 4650);
DISPLAY 0.829787 (-3600 4650);
DISPLAY INVISIBLE (-3600 4650);
FORCEPROP 1 LAST PATH I380
J 2
(-3098 4550);
DISPLAY 0.872340 (-3098 4550);
PAINT GREEN (-3098 4550);
DISPLAY INVISIBLE (-3098 4550);
FORCEPROP 2 LAST CDS_LIB standard
J 0
(-3100 4550);
DISPLAY INVISIBLE (-3100 4550);
FORCEADD TAP..6
R 2
(-3250 4800);
FORCEPROP 3 LASTPIN (-3300 4800) SIG_NAME P5E_CPU0_P0_TX_DP<10>
J 0
(-3290 4810);
DISPLAY 0.659574 (-3290 4810);
PAINT MONO (-3290 4810);
DISPLAY INVISIBLE (-3290 4810);
FORCEPROP 1 LASTPIN (-3300 4800) BN 10
J 2
(-3248 4808);
DISPLAY 0.680851 (-3248 4808);
PAINT MONO (-3248 4808);
FORCEPROP 2 LAST ROOM RISER1
J 0
(-3750 4850);
DISPLAY 0.829787 (-3750 4850);
PAINT RED (-3750 4850);
DISPLAY INVISIBLE (-3750 4850);
FORCEPROP 1 LAST HDL_TAP TRUE
J 2
(-3575 4675);
DISPLAY 0.702128 (-3575 4675);
PAINT GREEN (-3575 4675);
DISPLAY INVISIBLE (-3575 4675);
FORCEPROP 1 LAST BODY_TYPE PLUMBING
J 2
(-3250 4750);
DISPLAY 0.702128 (-3250 4750);
PAINT GREEN (-3250 4750);
DISPLAY INVISIBLE (-3250 4750);
FORCEPROP 2 LAST BOM_COST IO_SLOT
J 0
(-3750 4900);
DISPLAY 0.829787 (-3750 4900);
DISPLAY INVISIBLE (-3750 4900);
FORCEPROP 1 LAST PATH I381
J 2
(-3248 4800);
DISPLAY 0.872340 (-3248 4800);
PAINT GREEN (-3248 4800);
DISPLAY INVISIBLE (-3248 4800);
FORCEPROP 2 LAST CDS_LIB standard
J 0
(-3250 4800);
DISPLAY INVISIBLE (-3250 4800);
FORCEADD TAP..6
R 2
(-3250 4900);
FORCEPROP 3 LASTPIN (-3300 4900) SIG_NAME P5E_CPU0_P0_TX_DP<9>
J 0
(-3290 4910);
DISPLAY 0.659574 (-3290 4910);
PAINT MONO (-3290 4910);
DISPLAY INVISIBLE (-3290 4910);
FORCEPROP 1 LASTPIN (-3300 4900) BN 9
J 2
(-3248 4908);
DISPLAY 0.680851 (-3248 4908);
PAINT MONO (-3248 4908);
FORCEPROP 2 LAST ROOM RISER1
J 0
(-3750 4950);
DISPLAY 0.829787 (-3750 4950);
PAINT RED (-3750 4950);
DISPLAY INVISIBLE (-3750 4950);
FORCEPROP 1 LAST HDL_TAP TRUE
J 2
(-3575 4775);
DISPLAY 0.702128 (-3575 4775);
PAINT GREEN (-3575 4775);
DISPLAY INVISIBLE (-3575 4775);
FORCEPROP 1 LAST BODY_TYPE PLUMBING
J 2
(-3250 4850);
DISPLAY 0.702128 (-3250 4850);
PAINT GREEN (-3250 4850);
DISPLAY INVISIBLE (-3250 4850);
FORCEPROP 2 LAST BOM_COST IO_SLOT
J 0
(-3750 5000);
DISPLAY 0.829787 (-3750 5000);
DISPLAY INVISIBLE (-3750 5000);
FORCEPROP 1 LAST PATH I382
J 2
(-3248 4900);
DISPLAY 0.872340 (-3248 4900);
PAINT GREEN (-3248 4900);
DISPLAY INVISIBLE (-3248 4900);
FORCEPROP 2 LAST CDS_LIB standard
J 0
(-3250 4900);
DISPLAY INVISIBLE (-3250 4900);
FORCEADD TAP..6
R 2
(-3250 5000);
FORCEPROP 3 LASTPIN (-3300 5000) SIG_NAME P5E_CPU0_P0_TX_DP<8>
J 0
(-3290 5010);
DISPLAY 0.659574 (-3290 5010);
PAINT MONO (-3290 5010);
DISPLAY INVISIBLE (-3290 5010);
FORCEPROP 1 LASTPIN (-3300 5000) BN 8
J 2
(-3248 5008);
DISPLAY 0.680851 (-3248 5008);
PAINT MONO (-3248 5008);
FORCEPROP 2 LAST ROOM RISER1
J 0
(-3750 5050);
DISPLAY 0.829787 (-3750 5050);
PAINT RED (-3750 5050);
DISPLAY INVISIBLE (-3750 5050);
FORCEPROP 1 LAST HDL_TAP TRUE
J 2
(-3575 4875);
DISPLAY 0.702128 (-3575 4875);
PAINT GREEN (-3575 4875);
DISPLAY INVISIBLE (-3575 4875);
FORCEPROP 1 LAST BODY_TYPE PLUMBING
J 2
(-3250 4950);
DISPLAY 0.702128 (-3250 4950);
PAINT GREEN (-3250 4950);
DISPLAY INVISIBLE (-3250 4950);
FORCEPROP 2 LAST BOM_COST IO_SLOT
J 0
(-3750 5100);
DISPLAY 0.829787 (-3750 5100);
DISPLAY INVISIBLE (-3750 5100);
FORCEPROP 1 LAST PATH I383
J 2
(-3248 5000);
DISPLAY 0.872340 (-3248 5000);
PAINT GREEN (-3248 5000);
DISPLAY INVISIBLE (-3248 5000);
FORCEPROP 2 LAST CDS_LIB standard
J 0
(-3250 5000);
DISPLAY INVISIBLE (-3250 5000);
FORCEADD TAP..6
R 2
(-3250 4500);
FORCEPROP 3 LASTPIN (-3300 4500) SIG_NAME P5E_CPU0_P0_TX_DP<13>
J 0
(-3290 4510);
DISPLAY 0.659574 (-3290 4510);
PAINT MONO (-3290 4510);
DISPLAY INVISIBLE (-3290 4510);
FORCEPROP 1 LASTPIN (-3300 4500) BN 13
J 2
(-3248 4508);
DISPLAY 0.680851 (-3248 4508);
PAINT MONO (-3248 4508);
FORCEPROP 2 LAST ROOM RISER1
J 0
(-3750 4550);
DISPLAY 0.829787 (-3750 4550);
PAINT RED (-3750 4550);
DISPLAY INVISIBLE (-3750 4550);
FORCEPROP 1 LAST HDL_TAP TRUE
J 2
(-3575 4375);
DISPLAY 0.702128 (-3575 4375);
PAINT GREEN (-3575 4375);
DISPLAY INVISIBLE (-3575 4375);
FORCEPROP 1 LAST BODY_TYPE PLUMBING
J 2
(-3250 4450);
DISPLAY 0.702128 (-3250 4450);
PAINT GREEN (-3250 4450);
DISPLAY INVISIBLE (-3250 4450);
FORCEPROP 2 LAST BOM_COST IO_SLOT
J 0
(-3750 4600);
DISPLAY 0.829787 (-3750 4600);
DISPLAY INVISIBLE (-3750 4600);
FORCEPROP 1 LAST PATH I384
J 2
(-3248 4500);
DISPLAY 0.872340 (-3248 4500);
PAINT GREEN (-3248 4500);
DISPLAY INVISIBLE (-3248 4500);
FORCEPROP 2 LAST CDS_LIB standard
J 0
(-3250 4500);
DISPLAY INVISIBLE (-3250 4500);
FORCEADD TAP..6
R 2
(-3250 4700);
FORCEPROP 3 LASTPIN (-3300 4700) SIG_NAME P5E_CPU0_P0_TX_DP<11>
J 0
(-3290 4710);
DISPLAY 0.659574 (-3290 4710);
PAINT MONO (-3290 4710);
DISPLAY INVISIBLE (-3290 4710);
FORCEPROP 1 LASTPIN (-3300 4700) BN 11
J 2
(-3248 4708);
DISPLAY 0.680851 (-3248 4708);
PAINT MONO (-3248 4708);
FORCEPROP 2 LAST ROOM RISER1
J 0
(-3750 4750);
DISPLAY 0.829787 (-3750 4750);
PAINT RED (-3750 4750);
DISPLAY INVISIBLE (-3750 4750);
FORCEPROP 1 LAST HDL_TAP TRUE
J 2
(-3575 4575);
DISPLAY 0.702128 (-3575 4575);
PAINT GREEN (-3575 4575);
DISPLAY INVISIBLE (-3575 4575);
FORCEPROP 1 LAST BODY_TYPE PLUMBING
J 2
(-3250 4650);
DISPLAY 0.702128 (-3250 4650);
PAINT GREEN (-3250 4650);
DISPLAY INVISIBLE (-3250 4650);
FORCEPROP 2 LAST BOM_COST IO_SLOT
J 0
(-3750 4800);
DISPLAY 0.829787 (-3750 4800);
DISPLAY INVISIBLE (-3750 4800);
FORCEPROP 1 LAST PATH I385
J 2
(-3248 4700);
DISPLAY 0.872340 (-3248 4700);
PAINT GREEN (-3248 4700);
DISPLAY INVISIBLE (-3248 4700);
FORCEPROP 2 LAST CDS_LIB standard
J 0
(-3250 4700);
DISPLAY INVISIBLE (-3250 4700);
FORCEADD TAP..6
R 2
(-3250 4600);
FORCEPROP 3 LASTPIN (-3300 4600) SIG_NAME P5E_CPU0_P0_TX_DP<12>
J 0
(-3290 4610);
DISPLAY 0.659574 (-3290 4610);
PAINT MONO (-3290 4610);
DISPLAY INVISIBLE (-3290 4610);
FORCEPROP 1 LASTPIN (-3300 4600) BN 12
J 2
(-3248 4608);
DISPLAY 0.680851 (-3248 4608);
PAINT MONO (-3248 4608);
FORCEPROP 2 LAST ROOM RISER1
J 0
(-3750 4650);
DISPLAY 0.829787 (-3750 4650);
PAINT RED (-3750 4650);
DISPLAY INVISIBLE (-3750 4650);
FORCEPROP 1 LAST HDL_TAP TRUE
J 2
(-3575 4475);
DISPLAY 0.702128 (-3575 4475);
PAINT GREEN (-3575 4475);
DISPLAY INVISIBLE (-3575 4475);
FORCEPROP 1 LAST BODY_TYPE PLUMBING
J 2
(-3250 4550);
DISPLAY 0.702128 (-3250 4550);
PAINT GREEN (-3250 4550);
DISPLAY INVISIBLE (-3250 4550);
FORCEPROP 2 LAST BOM_COST IO_SLOT
J 0
(-3750 4700);
DISPLAY 0.829787 (-3750 4700);
DISPLAY INVISIBLE (-3750 4700);
FORCEPROP 1 LAST PATH I386
J 2
(-3248 4600);
DISPLAY 0.872340 (-3248 4600);
PAINT GREEN (-3248 4600);
DISPLAY INVISIBLE (-3248 4600);
FORCEPROP 2 LAST CDS_LIB standard
J 0
(-3250 4600);
DISPLAY INVISIBLE (-3250 4600);
FORCEADD TAP..6
R 2
(-3100 4450);
FORCEPROP 3 LASTPIN (-3150 4450) SIG_NAME P5E_CPU0_P0_TX_DN<13>
J 0
(-3140 4460);
DISPLAY 0.659574 (-3140 4460);
PAINT MONO (-3140 4460);
DISPLAY INVISIBLE (-3140 4460);
FORCEPROP 1 LASTPIN (-3150 4450) BN 13
J 2
(-3098 4458);
DISPLAY 0.680851 (-3098 4458);
PAINT MONO (-3098 4458);
FORCEPROP 2 LAST ROOM RISER1
J 0
(-3600 4500);
DISPLAY 0.829787 (-3600 4500);
PAINT RED (-3600 4500);
DISPLAY INVISIBLE (-3600 4500);
FORCEPROP 1 LAST HDL_TAP TRUE
J 2
(-3425 4325);
DISPLAY 0.702128 (-3425 4325);
PAINT GREEN (-3425 4325);
DISPLAY INVISIBLE (-3425 4325);
FORCEPROP 1 LAST BODY_TYPE PLUMBING
J 2
(-3100 4400);
DISPLAY 0.702128 (-3100 4400);
PAINT GREEN (-3100 4400);
DISPLAY INVISIBLE (-3100 4400);
FORCEPROP 2 LAST BOM_COST IO_SLOT
J 0
(-3600 4550);
DISPLAY 0.829787 (-3600 4550);
DISPLAY INVISIBLE (-3600 4550);
FORCEPROP 1 LAST PATH I387
J 2
(-3098 4450);
DISPLAY 0.872340 (-3098 4450);
PAINT GREEN (-3098 4450);
DISPLAY INVISIBLE (-3098 4450);
FORCEPROP 2 LAST CDS_LIB standard
J 0
(-3100 4450);
DISPLAY INVISIBLE (-3100 4450);
FORCEADD TAP..6
R 2
(-3100 4250);
FORCEPROP 3 LASTPIN (-3150 4250) SIG_NAME P5E_CPU0_P0_TX_DN<15>
J 0
(-3140 4260);
DISPLAY 0.659574 (-3140 4260);
PAINT MONO (-3140 4260);
DISPLAY INVISIBLE (-3140 4260);
FORCEPROP 1 LASTPIN (-3150 4250) BN 15
J 2
(-3098 4258);
DISPLAY 0.680851 (-3098 4258);
PAINT MONO (-3098 4258);
FORCEPROP 2 LAST ROOM RISER1
J 0
(-3600 4300);
DISPLAY 0.829787 (-3600 4300);
PAINT RED (-3600 4300);
DISPLAY INVISIBLE (-3600 4300);
FORCEPROP 1 LAST HDL_TAP TRUE
J 2
(-3425 4125);
DISPLAY 0.702128 (-3425 4125);
PAINT GREEN (-3425 4125);
DISPLAY INVISIBLE (-3425 4125);
FORCEPROP 1 LAST BODY_TYPE PLUMBING
J 2
(-3100 4200);
DISPLAY 0.702128 (-3100 4200);
PAINT GREEN (-3100 4200);
DISPLAY INVISIBLE (-3100 4200);
FORCEPROP 2 LAST BOM_COST IO_SLOT
J 0
(-3600 4350);
DISPLAY 0.829787 (-3600 4350);
DISPLAY INVISIBLE (-3600 4350);
FORCEPROP 1 LAST PATH I388
J 2
(-3098 4250);
DISPLAY 0.872340 (-3098 4250);
PAINT GREEN (-3098 4250);
DISPLAY INVISIBLE (-3098 4250);
FORCEPROP 2 LAST CDS_LIB standard
J 0
(-3100 4250);
DISPLAY INVISIBLE (-3100 4250);
FORCEADD TAP..6
R 2
(-3100 4350);
FORCEPROP 3 LASTPIN (-3150 4350) SIG_NAME P5E_CPU0_P0_TX_DN<14>
J 0
(-3140 4360);
DISPLAY 0.659574 (-3140 4360);
PAINT MONO (-3140 4360);
DISPLAY INVISIBLE (-3140 4360);
FORCEPROP 1 LASTPIN (-3150 4350) BN 14
J 2
(-3098 4358);
DISPLAY 0.680851 (-3098 4358);
PAINT MONO (-3098 4358);
FORCEPROP 2 LAST ROOM RISER1
J 0
(-3600 4400);
DISPLAY 0.829787 (-3600 4400);
PAINT RED (-3600 4400);
DISPLAY INVISIBLE (-3600 4400);
FORCEPROP 1 LAST HDL_TAP TRUE
J 2
(-3425 4225);
DISPLAY 0.702128 (-3425 4225);
PAINT GREEN (-3425 4225);
DISPLAY INVISIBLE (-3425 4225);
FORCEPROP 1 LAST BODY_TYPE PLUMBING
J 2
(-3100 4300);
DISPLAY 0.702128 (-3100 4300);
PAINT GREEN (-3100 4300);
DISPLAY INVISIBLE (-3100 4300);
FORCEPROP 2 LAST BOM_COST IO_SLOT
J 0
(-3600 4450);
DISPLAY 0.829787 (-3600 4450);
DISPLAY INVISIBLE (-3600 4450);
FORCEPROP 1 LAST PATH I389
J 2
(-3098 4350);
DISPLAY 0.872340 (-3098 4350);
PAINT GREEN (-3098 4350);
DISPLAY INVISIBLE (-3098 4350);
FORCEPROP 2 LAST CDS_LIB standard
J 0
(-3100 4350);
DISPLAY INVISIBLE (-3100 4350);
FORCEADD TAP..6
R 2
(-3250 4400);
FORCEPROP 3 LASTPIN (-3300 4400) SIG_NAME P5E_CPU0_P0_TX_DP<14>
J 0
(-3290 4410);
DISPLAY 0.659574 (-3290 4410);
PAINT MONO (-3290 4410);
DISPLAY INVISIBLE (-3290 4410);
FORCEPROP 1 LASTPIN (-3300 4400) BN 14
J 2
(-3248 4408);
DISPLAY 0.680851 (-3248 4408);
PAINT MONO (-3248 4408);
FORCEPROP 2 LAST ROOM RISER1
J 0
(-3750 4450);
DISPLAY 0.829787 (-3750 4450);
PAINT RED (-3750 4450);
DISPLAY INVISIBLE (-3750 4450);
FORCEPROP 1 LAST HDL_TAP TRUE
J 2
(-3575 4275);
DISPLAY 0.702128 (-3575 4275);
PAINT GREEN (-3575 4275);
DISPLAY INVISIBLE (-3575 4275);
FORCEPROP 1 LAST BODY_TYPE PLUMBING
J 2
(-3250 4350);
DISPLAY 0.702128 (-3250 4350);
PAINT GREEN (-3250 4350);
DISPLAY INVISIBLE (-3250 4350);
FORCEPROP 2 LAST BOM_COST IO_SLOT
J 0
(-3750 4500);
DISPLAY 0.829787 (-3750 4500);
DISPLAY INVISIBLE (-3750 4500);
FORCEPROP 1 LAST PATH I390
J 2
(-3248 4400);
DISPLAY 0.872340 (-3248 4400);
PAINT GREEN (-3248 4400);
DISPLAY INVISIBLE (-3248 4400);
FORCEPROP 2 LAST CDS_LIB standard
J 0
(-3250 4400);
DISPLAY INVISIBLE (-3250 4400);
FORCEADD TAP..6
R 2
(-3250 4300);
FORCEPROP 3 LASTPIN (-3300 4300) SIG_NAME P5E_CPU0_P0_TX_DP<15>
J 0
(-3290 4310);
DISPLAY 0.659574 (-3290 4310);
PAINT MONO (-3290 4310);
DISPLAY INVISIBLE (-3290 4310);
FORCEPROP 1 LASTPIN (-3300 4300) BN 15
J 2
(-3248 4308);
DISPLAY 0.680851 (-3248 4308);
PAINT MONO (-3248 4308);
FORCEPROP 2 LAST ROOM RISER1
J 0
(-3750 4350);
DISPLAY 0.829787 (-3750 4350);
PAINT RED (-3750 4350);
DISPLAY INVISIBLE (-3750 4350);
FORCEPROP 1 LAST HDL_TAP TRUE
J 2
(-3575 4175);
DISPLAY 0.702128 (-3575 4175);
PAINT GREEN (-3575 4175);
DISPLAY INVISIBLE (-3575 4175);
FORCEPROP 1 LAST BODY_TYPE PLUMBING
J 2
(-3250 4250);
DISPLAY 0.702128 (-3250 4250);
PAINT GREEN (-3250 4250);
DISPLAY INVISIBLE (-3250 4250);
FORCEPROP 2 LAST BOM_COST IO_SLOT
J 0
(-3750 4400);
DISPLAY 0.829787 (-3750 4400);
DISPLAY INVISIBLE (-3750 4400);
FORCEPROP 1 LAST PATH I391
J 2
(-3248 4300);
DISPLAY 0.872340 (-3248 4300);
PAINT GREEN (-3248 4300);
DISPLAY INVISIBLE (-3248 4300);
FORCEPROP 2 LAST CDS_LIB standard
J 0
(-3250 4300);
DISPLAY INVISIBLE (-3250 4300);
FORCEADD OFFPAGE..2
(-1725 6025);
FORCEPROP 1 LAST OFFPAGE TRUE
J 0
(-1400 5900);
DISPLAY 0.872340 (-1400 5900);
PAINT GREEN (-1400 5900);
DISPLAY INVISIBLE (-1400 5900);
FORCEPROP 1 LAST COMMENT_BODY TRUE
J 0
(-1770 5930);
DISPLAY 0.872340 (-1770 5930);
PAINT GREEN (-1770 5930);
DISPLAY INVISIBLE (-1770 5930);
FORCEPROP 2 LAST PATH I392
J 0
(-1550 6100);
DISPLAY 0.680851 (-1550 6100);
DISPLAY INVISIBLE (-1550 6100);
FORCEPROP 2 LAST CDS_LIB standard
J 0
(-1725 6025);
DISPLAY INVISIBLE (-1725 6025);
FORCEADD OFFPAGE..2
(-1725 5975);
FORCEPROP 2 LAST CDS_LIB standard
J 0
(-1725 5975);
DISPLAY INVISIBLE (-1725 5975);
FORCEPROP 2 LAST PATH I393
J 0
(-1550 6050);
DISPLAY 0.680851 (-1550 6050);
DISPLAY INVISIBLE (-1550 6050);
FORCEPROP 1 LAST OFFPAGE TRUE
J 0
(-1400 5850);
DISPLAY 0.872340 (-1400 5850);
PAINT GREEN (-1400 5850);
DISPLAY INVISIBLE (-1400 5850);
FORCEPROP 1 LAST COMMENT_BODY TRUE
J 0
(-1770 5880);
DISPLAY 0.872340 (-1770 5880);
PAINT GREEN (-1770 5880);
DISPLAY INVISIBLE (-1770 5880);
FORCEADD QUANTA_TITLE_BLOCK_C..1
(-100 100);
FORCEPROP 0 LAST CDS_CON_LAST_MODIFIED Fri Mar 11 14:52:19 2022
J 0
(-1985 115);
DISPLAY INVISIBLE (-1985 115);
FORCEPROP 1 LAST CUSTOM_TXT_CDS <CON_LAST_MODIFIED>
J 0
(-1985 115);
DISPLAY 0.978723 (-1985 115);
FORCEPROP 2 LAST CUSTOM_TXT_CDS <XR_PAGE_TITLE>
J 0
(-7990 5350);
DISPLAY 0.638298 (-7990 5350);
PAINT PINK (-7990 5350);
DISPLAY INVISIBLE (-7990 5350);
FORCEPROP 1 LAST CUSTOM_TXT_CDS <NAME_2>
J 0
(-3275 150);
FORCEPROP 1 LAST CUSTOM_TXT_CDS <NAME_1>
J 0
(-3275 275);
FORCEPROP 1 LAST CUSTOM_TXT_CDS <Q_NUMBER>
J 0
(-1503 203);
DISPLAY 1.212766 (-1503 203);
FORCEPROP 1 LAST CUSTOM_TXT_CDS <Q_PROJ>
J 0
(-2482 202);
DISPLAY 1.212766 (-2482 202);
FORCEPROP 1 LAST CUSTOM_TXT_CDS <Q_REV>
J 0
(-284 203);
DISPLAY 1.212766 (-284 203);
FORCEPROP 1 LAST CUSTOM_TXT_CDS <CON_PAGE_NUM> OF <CON_TOTAL_PAGES>
J 0
(-546 118);
DISPLAY 0.978723 (-546 118);
FORCEPROP 1 LAST Q_DEPT BU9
J 1
(-3863 149);
DISPLAY 1.957447 (-3863 149);
PAINT GREEN (-3863 149);
FORCEPROP 1 LAST Q_TITLE CPU0 PCIE P0/P1
J 0
(-9400 150);
DISPLAY 2.446809 (-9400 150);
PAINT GREEN (-9400 150);
FORCEPROP 1 LAST COMMENT_BODY TRUE
J 0
(-88 87);
DISPLAY 0.978723 (-88 87);
PAINT GREEN (-88 87);
DISPLAY INVISIBLE (-88 87);
FORCEPROP 2 LAST PAGE_BORDER TRUE
J 0
(-7990 5350);
DISPLAY 0.638298 (-7990 5350);
PAINT PINK (-7990 5350);
DISPLAY INVISIBLE (-7990 5350);
FORCEPROP 1 LAST CDS_LMAN_SYM_OUTLINE -9475,6775,100,-125
J 0
(-100 100);
DISPLAY 0.468085 (-100 100);
PAINT GREEN (-100 100);
DISPLAY INVISIBLE (-100 100);
FORCEPROP 2 LAST CDS_LIB pure_quanta
J 0
(-100 100);
DISPLAY INVISIBLE (-100 100);
FORCEPROP 2 LAST CDS_XR_PAGE_TITLE CR-24 : @T6G_MB_LIB.T6G(SCH_1):PAGE24
J 0
(-7990 5350);
DISPLAY 0.638298 (-7990 5350);
PAINT PINK (-7990 5350);
DISPLAY INVISIBLE (-7990 5350);
WIRE 17 -1 (-3050 4575)(-3050 4475);
WIRE 17 -1 (-3050 4675)(-3050 4575);
WIRE 17 -1 (-3050 4475)(-3050 4375);
WIRE 17 -1 (-3050 4375)(-3050 4275);
WIRE 17 -1 (-3050 4775)(-3050 4675);
WIRE 17 -1 (-3050 4875)(-3050 4775);
WIRE 17 -1 (-3050 4975)(-3050 4875);
WIRE 17 -1 (-3050 5075)(-3050 4975);
WIRE 17 -1 (-3050 5175)(-3050 5075);
WIRE 17 -1 (-3050 5275)(-3050 5175);
WIRE 17 -1 (-3050 5375)(-3050 5275);
WIRE 17 -1 (-3050 5475)(-3050 5375);
WIRE 17 -1 (-3050 5575)(-3050 5475);
WIRE 17 -1 (-3050 5675)(-3050 5575);
WIRE 17 -1 (-3050 5775)(-3050 5675);
WIRE 17 -1 (-3050 5975)(-3050 5775);
WIRE 17 -1 (-3050 5975)(-1775 5975);
FORCEPROP 2 LAST SIG_NAME P5E_CPU0_P0_TX_DN<15:0>
J 0
(-2810 5985);
DISPLAY 0.489362 (-2810 5985);
WIRE 17 -1 (-3200 4525)(-3200 4425);
WIRE 17 -1 (-3200 4625)(-3200 4525);
WIRE 17 -1 (-3200 4425)(-3200 4325);
WIRE 17 -1 (-3200 4725)(-3200 4625);
WIRE 17 -1 (-3200 4825)(-3200 4725);
WIRE 17 -1 (-3200 4925)(-3200 4825);
WIRE 17 -1 (-3200 5025)(-3200 4925);
WIRE 17 -1 (-3200 5125)(-3200 5025);
WIRE 17 -1 (-3200 5225)(-3200 5125);
WIRE 17 -1 (-3200 5325)(-3200 5225);
WIRE 17 -1 (-3200 5425)(-3200 5325);
WIRE 17 -1 (-3200 5525)(-3200 5425);
WIRE 17 -1 (-3200 5625)(-3200 5525);
WIRE 17 -1 (-3200 5725)(-3200 5625);
WIRE 17 -1 (-3200 5825)(-3200 5725);
WIRE 17 -1 (-3200 6025)(-3200 5825);
WIRE 17 -1 (-3200 6025)(-1775 6025);
FORCEPROP 2 LAST SIG_NAME P5E_CPU0_P0_TX_DP<15:0>
J 0
(-2810 6060);
DISPLAY 0.489362 (-2810 6060);
WIRE 17 -1 (-6875 4875)(-6875 4975);
WIRE 17 -1 (-6875 4775)(-6875 4875);
WIRE 17 -1 (-6875 4975)(-6875 5075);
WIRE 17 -1 (-6875 5075)(-6875 5175);
WIRE 17 -1 (-6875 4675)(-6875 4775);
WIRE 17 -1 (-6875 4575)(-6875 4675);
WIRE 17 -1 (-6875 5175)(-6875 5275);
WIRE 17 -1 (-6875 5275)(-6875 5375);
WIRE 17 -1 (-6875 4475)(-6875 4575);
WIRE 17 -1 (-6875 4375)(-6875 4475);
WIRE 17 -1 (-6875 5375)(-6875 5475);
WIRE 17 -1 (-6875 5475)(-6875 5575);
WIRE 17 -1 (-6875 4275)(-6875 4375);
WIRE 17 -1 (-6875 5575)(-6875 5675);
WIRE 17 -1 (-6875 5675)(-6875 5775);
WIRE 17 -1 (-6875 5775)(-6875 5975);
WIRE 17 -1 (-8000 5975)(-6875 5975);
FORCEPROP 2 LAST SIG_NAME P5E_CPU0_P0_RX_DN<15:0>
J 0
(-7735 5985);
DISPLAY 0.489362 (-7735 5985);
WIRE 17 -1 (-6725 4825)(-6725 4925);
WIRE 17 -1 (-6725 4725)(-6725 4825);
WIRE 17 -1 (-6725 4925)(-6725 5025);
WIRE 17 -1 (-6725 5025)(-6725 5125);
WIRE 17 -1 (-6725 4625)(-6725 4725);
WIRE 17 -1 (-6725 4525)(-6725 4625);
WIRE 17 -1 (-6725 5125)(-6725 5225);
WIRE 17 -1 (-6725 5225)(-6725 5325);
WIRE 17 -1 (-6725 4425)(-6725 4525);
WIRE 17 -1 (-6725 4325)(-6725 4425);
WIRE 17 -1 (-6725 5325)(-6725 5425);
WIRE 17 -1 (-6725 5425)(-6725 5525);
WIRE 17 -1 (-6725 5525)(-6725 5625);
WIRE 17 -1 (-6725 5625)(-6725 5725);
WIRE 17 -1 (-6725 5725)(-6725 5825);
WIRE 17 -1 (-6725 5825)(-6725 6025);
WIRE 17 -1 (-8000 6025)(-6725 6025);
FORCEPROP 2 LAST SIG_NAME P5E_CPU0_P0_RX_DP<15:0>
J 0
(-7735 6060);
DISPLAY 0.489362 (-7735 6060);
WIRE 17 -1 (-3125 1800)(-3125 1700);
WIRE 17 -1 (-3125 1900)(-3125 1800);
WIRE 17 -1 (-3125 1700)(-3125 1600);
WIRE 17 -1 (-3125 1600)(-3125 1500);
WIRE 17 -1 (-3125 2000)(-3125 1900);
WIRE 17 -1 (-3125 2100)(-3125 2000);
WIRE 17 -1 (-3125 1500)(-3125 1400);
WIRE 17 -1 (-3125 1400)(-3125 1300);
WIRE 17 -1 (-3125 2200)(-3125 2100);
WIRE 17 -1 (-3125 2300)(-3125 2200);
WIRE 17 -1 (-3125 1300)(-3125 1200);
WIRE 17 -1 (-3125 1200)(-3125 1100);
WIRE 17 -1 (-3125 2500)(-3125 2300);
WIRE 17 -1 (-3125 2500)(-1850 2500);
FORCEPROP 2 LAST SIG_NAME P5E_CPU0_P1_TX_DN<15:0>
J 2
(-1875 2510);
DISPLAY 0.489362 (-1875 2510);
WIRE 17 -1 (-3275 2150)(-3275 2050);
WIRE 17 -1 (-3275 2250)(-3275 2150);
WIRE 17 -1 (-3275 2050)(-3275 1950);
WIRE 17 -1 (-3275 1950)(-3275 1850);
WIRE 17 -1 (-3275 2350)(-3275 2250);
WIRE 17 -1 (-3275 2550)(-3275 2350);
WIRE 17 -1 (-3275 1850)(-3275 1750);
WIRE 17 -1 (-3275 1750)(-3275 1650);
WIRE 17 -1 (-3275 2550)(-1850 2550);
FORCEPROP 2 LAST SIG_NAME P5E_CPU0_P1_TX_DP<15:0>
J 2
(-1875 2560);
DISPLAY 0.489362 (-1875 2560);
WIRE 17 -1 (-3125 1100)(-3125 1000);
WIRE 17 -1 (-3125 1000)(-3125 900);
WIRE 17 -1 (-3125 900)(-3125 800);
WIRE 17 -1 (-3275 1650)(-3275 1550);
WIRE 17 -1 (-3275 1550)(-3275 1450);
WIRE 17 -1 (-3275 1450)(-3275 1350);
WIRE 17 -1 (-3275 1350)(-3275 1250);
WIRE 17 -1 (-3275 1250)(-3275 1150);
WIRE 17 -1 (-3275 1150)(-3275 1050);
WIRE 17 -1 (-3275 1050)(-3275 950);
WIRE 17 -1 (-3275 950)(-3275 850);
WIRE 17 -1 (-6950 1000)(-6950 1100);
WIRE 17 -1 (-6950 900)(-6950 1000);
WIRE 17 -1 (-6950 1100)(-6950 1200);
WIRE 17 -1 (-6950 1200)(-6950 1300);
WIRE 17 -1 (-6950 800)(-6950 900);
WIRE 17 -1 (-6950 1300)(-6950 1400);
WIRE 17 -1 (-6950 1400)(-6950 1500);
WIRE 17 -1 (-6950 1500)(-6950 1600);
WIRE 17 -1 (-6950 1600)(-6950 1700);
WIRE 17 -1 (-6950 1700)(-6950 1800);
WIRE 17 -1 (-6950 1800)(-6950 1900);
WIRE 17 -1 (-6950 1900)(-6950 2000);
WIRE 17 -1 (-6950 2000)(-6950 2100);
WIRE 17 -1 (-6950 2100)(-6950 2200);
WIRE 17 -1 (-6950 2200)(-6950 2300);
WIRE 17 -1 (-6950 2300)(-6950 2500);
WIRE 17 -1 (-8075 2500)(-6950 2500);
FORCEPROP 2 LAST SIG_NAME P5E_CPU0_P1_RX_DN<15:0>
J 0
(-8025 2510);
DISPLAY 0.489362 (-8025 2510);
WIRE 17 -1 (-6800 850)(-6800 950);
WIRE 17 -1 (-6800 950)(-6800 1050);
WIRE 17 -1 (-6800 1050)(-6800 1150);
WIRE 17 -1 (-6800 1150)(-6800 1250);
WIRE 17 -1 (-6800 1250)(-6800 1350);
WIRE 17 -1 (-6800 1350)(-6800 1450);
WIRE 17 -1 (-6800 1450)(-6800 1550);
WIRE 17 -1 (-6800 1550)(-6800 1650);
WIRE 17 -1 (-6800 1650)(-6800 1750);
WIRE 17 -1 (-6800 1750)(-6800 1850);
WIRE 17 -1 (-6800 1850)(-6800 1950);
WIRE 17 -1 (-6800 1950)(-6800 2050);
WIRE 17 -1 (-6800 2050)(-6800 2150);
WIRE 17 -1 (-6800 2150)(-6800 2250);
WIRE 17 -1 (-6800 2250)(-6800 2350);
WIRE 17 -1 (-6800 2350)(-6800 2550);
WIRE 17 -1 (-8075 2550)(-6800 2550);
FORCEPROP 2 LAST SIG_NAME P5E_CPU0_P1_RX_DP<15:0>
J 0
(-8025 2560);
DISPLAY 0.489362 (-8025 2560);
WIRE 16 -1 (-3750 2175)(-3225 2175);
WIRE 16 -1 (-3750 2075)(-3225 2075);
WIRE 16 -1 (-3750 1275)(-3225 1275);
WIRE 16 -1 (-3750 1175)(-3225 1175);
WIRE 16 -1 (-3750 1125)(-3375 1125);
WIRE 16 -1 (-3750 1075)(-3225 1075);
WIRE 16 -1 (-3750 1025)(-3375 1025);
WIRE 16 -1 (-3750 875)(-3225 875);
WIRE 16 -1 (-3750 2275)(-3225 2275);
WIRE 16 -1 (-3750 2225)(-3375 2225);
WIRE 16 -1 (-3750 2325)(-3375 2325);
WIRE 16 -1 (-6700 2225)(-6250 2225);
WIRE 16 -1 (-6850 2275)(-6250 2275);
WIRE 16 -1 (-6700 2325)(-6250 2325);
WIRE 16 -1 (-3675 5750)(-3150 5750);
WIRE 16 -1 (-3675 5700)(-3300 5700);
WIRE 16 -1 (-3675 5800)(-3300 5800);
WIRE 16 -1 (-3675 4850)(-3150 4850);
WIRE 16 -1 (-3675 4800)(-3300 4800);
WIRE 16 -1 (-3675 4900)(-3300 4900);
WIRE 16 -1 (-3675 4950)(-3150 4950);
WIRE 16 -1 (-3675 5000)(-3300 5000);
WIRE 16 -1 (-3675 5050)(-3150 5050);
WIRE 16 -1 (-3675 5150)(-3150 5150);
WIRE 16 -1 (-3675 5250)(-3150 5250);
WIRE 16 -1 (-3675 5450)(-3150 5450);
WIRE 16 -1 (-3675 5300)(-3300 5300);
WIRE 16 -1 (-3675 5200)(-3300 5200);
WIRE 16 -1 (-3675 5100)(-3300 5100);
WIRE 16 -1 (-3675 4650)(-3150 4650);
WIRE 16 -1 (-3675 4500)(-3300 4500);
WIRE 16 -1 (-3675 4350)(-3150 4350);
WIRE 16 -1 (-3675 4750)(-3150 4750);
WIRE 16 -1 (-3675 4700)(-3300 4700);
WIRE 16 -1 (-3750 1925)(-3375 1925);
WIRE 16 -1 (-3750 1875)(-3225 1875);
WIRE 16 -1 (-3750 1975)(-3225 1975);
WIRE 16 -1 (-6850 1775)(-6250 1775);
WIRE 16 -1 (-6850 1875)(-6250 1875);
WIRE 16 -1 (-6850 1975)(-6250 1975);
WIRE 16 -1 (-3675 5650)(-3150 5650);
WIRE 16 -1 (-6850 875)(-6250 875);
WIRE 16 -1 (-6850 775)(-6250 775);
WIRE 16 -1 (-6700 925)(-6250 925);
WIRE 16 -1 (-6850 1075)(-6250 1075);
WIRE 16 -1 (-6850 1175)(-6250 1175);
WIRE 16 -1 (-6850 1275)(-6250 1275);
WIRE 16 -1 (-6850 1375)(-6250 1375);
WIRE 16 -1 (-6850 1475)(-6250 1475);
WIRE 16 -1 (-6700 1125)(-6250 1125);
WIRE 16 -1 (-6700 1025)(-6250 1025);
WIRE 16 -1 (-6700 1225)(-6250 1225);
WIRE 16 -1 (-6700 1325)(-6250 1325);
WIRE 16 -1 (-6700 1425)(-6250 1425);
WIRE 16 -1 (-6700 1525)(-6250 1525);
WIRE 16 -1 (-6850 1575)(-6250 1575);
WIRE 16 -1 (-6850 1675)(-6250 1675);
WIRE 16 -1 (-6700 1625)(-6250 1625);
WIRE 16 -1 (-6700 1725)(-6250 1725);
WIRE 16 -1 (-6700 1825)(-6250 1825);
WIRE 16 -1 (-6700 1925)(-6250 1925);
WIRE 16 -1 (-6700 2025)(-6250 2025);
WIRE 16 -1 (-6850 2175)(-6250 2175);
WIRE 16 -1 (-6850 2075)(-6250 2075);
WIRE 16 -1 (-6700 2125)(-6250 2125);
WIRE 16 -1 (-6700 825)(-6250 825);
WIRE 16 -1 (-6850 975)(-6250 975);
WIRE 16 -1 (-3750 825)(-3375 825);
WIRE 16 -1 (-3750 925)(-3375 925);
WIRE 16 -1 (-3225 775)(-3750 775);
WIRE 16 -1 (-3750 975)(-3225 975);
WIRE 16 -1 (-3750 1225)(-3375 1225);
WIRE 16 -1 (-3750 1525)(-3375 1525);
WIRE 16 -1 (-3750 1425)(-3375 1425);
WIRE 16 -1 (-3750 1325)(-3375 1325);
WIRE 16 -1 (-3750 1375)(-3225 1375);
WIRE 16 -1 (-3750 1475)(-3225 1475);
WIRE 16 -1 (-3750 1725)(-3375 1725);
WIRE 16 -1 (-3750 1625)(-3375 1625);
WIRE 16 -1 (-3750 2025)(-3375 2025);
WIRE 16 -1 (-3750 1825)(-3375 1825);
WIRE 16 -1 (-3750 1575)(-3225 1575);
WIRE 16 -1 (-3750 1675)(-3225 1675);
WIRE 16 -1 (-6625 4700)(-6175 4700);
WIRE 16 -1 (-6775 4650)(-6175 4650);
WIRE 16 -1 (-6625 4500)(-6175 4500);
WIRE 16 -1 (-6775 4850)(-6175 4850);
WIRE 16 -1 (-6775 4750)(-6175 4750);
WIRE 16 -1 (-6775 4550)(-6175 4550);
WIRE 16 -1 (-6625 5000)(-6175 5000);
WIRE 16 -1 (-6625 4400)(-6175 4400);
WIRE 16 -1 (-6625 5200)(-6175 5200);
WIRE 16 -1 (-6775 5250)(-6175 5250);
WIRE 16 -1 (-6625 5300)(-6175 5300);
WIRE 16 -1 (-3675 5350)(-3150 5350);
WIRE 16 -1 (-6775 5050)(-6175 5050);
WIRE 16 -1 (-6775 5350)(-6175 5350);
WIRE 16 -1 (-6625 5400)(-6175 5400);
WIRE 16 -1 (-6625 5100)(-6175 5100);
WIRE 16 -1 (-6775 5150)(-6175 5150);
WIRE 16 -1 (-6625 4800)(-6175 4800);
WIRE 16 -1 (-6625 4600)(-6175 4600);
WIRE 16 -1 (-6775 4450)(-6175 4450);
WIRE 16 -1 (-6625 4300)(-6175 4300);
WIRE 16 -1 (-6775 4250)(-6175 4250);
WIRE 16 -1 (-6625 5600)(-6175 5600);
WIRE 16 -1 (-6775 5550)(-6175 5550);
WIRE 16 -1 (-6625 5500)(-6175 5500);
WIRE 16 -1 (-6775 5450)(-6175 5450);
WIRE 16 -1 (-6625 5800)(-6175 5800);
WIRE 16 -1 (-6775 4350)(-6175 4350);
WIRE 16 -1 (-6775 5650)(-6175 5650);
WIRE 16 -1 (-6625 5700)(-6175 5700);
WIRE 16 -1 (-6775 5750)(-6175 5750);
WIRE 16 -1 (-3675 5600)(-3300 5600);
WIRE 16 -1 (-3750 2125)(-3375 2125);
WIRE 16 -1 (-3675 5400)(-3300 5400);
WIRE 16 -1 (-3675 5500)(-3300 5500);
WIRE 16 -1 (-3750 1775)(-3225 1775);
WIRE 16 -1 (-3675 4600)(-3300 4600);
WIRE 16 -1 (-3150 4250)(-3675 4250);
WIRE 16 -1 (-3675 4300)(-3300 4300);
WIRE 16 -1 (-6625 4900)(-6175 4900);
WIRE 16 -1 (-6775 4950)(-6175 4950);
WIRE 16 -1 (-3675 4400)(-3300 4400);
WIRE 16 -1 (-3675 4450)(-3150 4450);
WIRE 16 -1 (-3675 5550)(-3150 5550);
WIRE 16 -1 (-3675 4550)(-3150 4550);
FORCENOTE
CPU0 P0[15:0] TO EXAMAX
(-2650 5100) 0;
DISPLAY LEFT (-2650 5100);
DISPLAY 2.000000 (-2650 5100);
FORCENOTE
CPU0 P1[15:0] TO EXAMAX
(-2775 1475) 0;
DISPLAY LEFT (-2775 1475);
DISPLAY 2.000000 (-2775 1475);
QUIT
